FILE_TYPE = MACRO_DRAWING;
SET COLOR_WIRE YELLOW;
SET COLOR_PROP ORANGE;
SET COLOR_DOT WHITE;
SET COLOR_ARC YELLOW;
SET COLOR_BODY GREEN;
SET COLOR_NOTE PURPLE;
SET PROP_DISPLAY VALUE;
SET PAGE_NUMBER P47;
FORCEADD GENOA_SP5..36
(-4500 3525);
FORCEPROP 1 LAST LOCATION U26
J 0
(-5145 6356);
DISPLAY 0.489362 (-5145 6356);
PAINT SKYBLUE (-5145 6356);
FORCEPROP 0 LAST $SEC 36
J 0
(-5125 6400);
DISPLAY 0.680851 (-5125 6400);
PAINT MONO (-5125 6400);
DISPLAY INVISIBLE (-5125 6400);
FORCEPROP 0 LAST CDS_SEC 36
J 0
(-5150 6350);
DISPLAY 1.021277 (-5150 6350);
DISPLAY INVISIBLE (-5150 6350);
FORCEPROP 0 LASTPIN (-5300 2900) $PN BC5
J 2
(-5310 2910);
DISPLAY 0.489362 (-5310 2910);
PAINT MONO (-5310 2910);
FORCEPROP 0 LASTPIN (-5300 2850) $PN BD6
J 2
(-5310 2860);
DISPLAY 0.489362 (-5310 2860);
PAINT MONO (-5310 2860);
FORCEPROP 0 LASTPIN (-5300 1750) $PN BF6
J 2
(-5310 1760);
DISPLAY 0.489362 (-5310 1760);
PAINT MONO (-5310 1760);
FORCEPROP 0 LASTPIN (-5300 1700) $PN BG5
J 2
(-5310 1710);
DISPLAY 0.489362 (-5310 1710);
PAINT MONO (-5310 1710);
FORCEPROP 0 LASTPIN (-5300 2050) $PN AT7
J 2
(-5310 2060);
DISPLAY 0.489362 (-5310 2060);
PAINT MONO (-5310 2060);
FORCEPROP 0 LASTPIN (-5300 1950) $PN AU7
J 2
(-5310 1960);
DISPLAY 0.489362 (-5310 1960);
PAINT MONO (-5310 1960);
FORCEPROP 0 LASTPIN (-5300 2750) $PN AU5
J 2
(-5310 2760);
DISPLAY 0.489362 (-5310 2760);
PAINT MONO (-5310 2760);
FORCEPROP 0 LASTPIN (-5300 2700) $PN AV7
J 2
(-5310 2710);
DISPLAY 0.489362 (-5310 2710);
PAINT MONO (-5310 2710);
FORCEPROP 0 LASTPIN (-5300 2600) $PN BN7
J 2
(-5310 2610);
DISPLAY 0.489362 (-5310 2610);
PAINT MONO (-5310 2610);
FORCEPROP 0 LASTPIN (-5300 1600) $PN AV6
J 2
(-5310 1610);
DISPLAY 0.489362 (-5310 1610);
PAINT MONO (-5310 1610);
FORCEPROP 0 LASTPIN (-5300 1550) $PN AW7
J 2
(-5310 1560);
DISPLAY 0.489362 (-5310 1560);
PAINT MONO (-5310 1560);
FORCEPROP 0 LASTPIN (-5300 1450) $PN BP7
J 2
(-5310 1460);
DISPLAY 0.489362 (-5310 1460);
PAINT MONO (-5310 1460);
FORCEPROP 0 LASTPIN (-5300 3750) $PN AW5
J 2
(-5310 3760);
DISPLAY 0.489362 (-5310 3760);
PAINT MONO (-5310 3760);
FORCEPROP 0 LASTPIN (-5300 3700) $PN AY6
J 2
(-5310 3710);
DISPLAY 0.489362 (-5310 3710);
PAINT MONO (-5310 3710);
FORCEPROP 0 LASTPIN (-5300 3650) $PN AY7
J 2
(-5310 3660);
DISPLAY 0.489362 (-5310 3660);
PAINT MONO (-5310 3660);
FORCEPROP 0 LASTPIN (-5300 3600) $PN BA7
J 2
(-5310 3610);
DISPLAY 0.489362 (-5310 3610);
PAINT MONO (-5310 3610);
FORCEPROP 0 LASTPIN (-5300 3550) $PN BA5
J 2
(-5310 3560);
DISPLAY 0.489362 (-5310 3560);
PAINT MONO (-5310 3560);
FORCEPROP 0 LASTPIN (-5300 3500) $PN BB6
J 2
(-5310 3510);
DISPLAY 0.489362 (-5310 3510);
PAINT MONO (-5310 3510);
FORCEPROP 0 LASTPIN (-5300 3450) $PN BB7
J 2
(-5310 3460);
DISPLAY 0.489362 (-5310 3460);
PAINT MONO (-5310 3460);
FORCEPROP 0 LASTPIN (-3700 2300) $PN AJ5
J 0
(-3690 2310);
DISPLAY 0.489362 (-3690 2310);
PAINT MONO (-3690 2310);
FORCEPROP 0 LASTPIN (-3700 2250) $PN AK7
J 0
(-3690 2260);
DISPLAY 0.489362 (-3690 2260);
PAINT MONO (-3690 2260);
FORCEPROP 0 LASTPIN (-3700 2200) $PN AK6
J 0
(-3690 2210);
DISPLAY 0.489362 (-3690 2210);
PAINT MONO (-3690 2210);
FORCEPROP 0 LASTPIN (-3700 2150) $PN AL7
J 0
(-3690 2160);
DISPLAY 0.489362 (-3690 2160);
PAINT MONO (-3690 2160);
FORCEPROP 0 LASTPIN (-3700 2100) $PN AN5
J 0
(-3690 2110);
DISPLAY 0.489362 (-3690 2110);
PAINT MONO (-3690 2110);
FORCEPROP 0 LASTPIN (-3700 2050) $PN AP7
J 0
(-3690 2060);
DISPLAY 0.489362 (-3690 2060);
PAINT MONO (-3690 2060);
FORCEPROP 0 LASTPIN (-3700 2000) $PN AP6
J 0
(-3690 2010);
DISPLAY 0.489362 (-3690 2010);
PAINT MONO (-3690 2010);
FORCEPROP 0 LASTPIN (-3700 1950) $PN AR7
J 0
(-3690 1960);
DISPLAY 0.489362 (-3690 1960);
PAINT MONO (-3690 1960);
FORCEPROP 0 LASTPIN (-3700 5900) $PN E5
J 0
(-3690 5910);
DISPLAY 0.489362 (-3690 5910);
PAINT MONO (-3690 5910);
FORCEPROP 0 LASTPIN (-3700 5850) $PN F7
J 0
(-3690 5860);
DISPLAY 0.489362 (-3690 5860);
PAINT MONO (-3690 5860);
FORCEPROP 0 LASTPIN (-3700 5800) $PN F6
J 0
(-3690 5810);
DISPLAY 0.489362 (-3690 5810);
PAINT MONO (-3690 5810);
FORCEPROP 0 LASTPIN (-3700 5750) $PN G7
J 0
(-3690 5760);
DISPLAY 0.489362 (-3690 5760);
PAINT MONO (-3690 5760);
FORCEPROP 0 LASTPIN (-3700 5700) $PN J5
J 0
(-3690 5710);
DISPLAY 0.489362 (-3690 5710);
PAINT MONO (-3690 5710);
FORCEPROP 0 LASTPIN (-3700 5650) $PN K7
J 0
(-3690 5660);
DISPLAY 0.489362 (-3690 5660);
PAINT MONO (-3690 5660);
FORCEPROP 0 LASTPIN (-3700 5600) $PN K6
J 0
(-3690 5610);
DISPLAY 0.489362 (-3690 5610);
PAINT MONO (-3690 5610);
FORCEPROP 0 LASTPIN (-3700 5550) $PN L7
J 0
(-3690 5560);
DISPLAY 0.489362 (-3690 5560);
PAINT MONO (-3690 5560);
FORCEPROP 0 LASTPIN (-3700 5450) $PN L5
J 0
(-3690 5460);
DISPLAY 0.489362 (-3690 5460);
PAINT MONO (-3690 5460);
FORCEPROP 0 LASTPIN (-3700 5400) $PN M7
J 0
(-3690 5410);
DISPLAY 0.489362 (-3690 5410);
PAINT MONO (-3690 5410);
FORCEPROP 0 LASTPIN (-3700 5350) $PN M6
J 0
(-3690 5360);
DISPLAY 0.489362 (-3690 5360);
PAINT MONO (-3690 5360);
FORCEPROP 0 LASTPIN (-3700 5300) $PN N7
J 0
(-3690 5310);
DISPLAY 0.489362 (-3690 5310);
PAINT MONO (-3690 5310);
FORCEPROP 0 LASTPIN (-3700 5250) $PN R5
J 0
(-3690 5260);
DISPLAY 0.489362 (-3690 5260);
PAINT MONO (-3690 5260);
FORCEPROP 0 LASTPIN (-3700 5200) $PN T7
J 0
(-3690 5210);
DISPLAY 0.489362 (-3690 5210);
PAINT MONO (-3690 5210);
FORCEPROP 0 LASTPIN (-3700 5150) $PN T6
J 0
(-3690 5160);
DISPLAY 0.489362 (-3690 5160);
PAINT MONO (-3690 5160);
FORCEPROP 0 LASTPIN (-3700 5100) $PN U7
J 0
(-3690 5110);
DISPLAY 0.489362 (-3690 5110);
PAINT MONO (-3690 5110);
FORCEPROP 0 LASTPIN (-3700 5000) $PN U5
J 0
(-3690 5010);
DISPLAY 0.489362 (-3690 5010);
PAINT MONO (-3690 5010);
FORCEPROP 0 LASTPIN (-3700 4950) $PN V7
J 0
(-3690 4960);
DISPLAY 0.489362 (-3690 4960);
PAINT MONO (-3690 4960);
FORCEPROP 0 LASTPIN (-3700 4900) $PN V6
J 0
(-3690 4910);
DISPLAY 0.489362 (-3690 4910);
PAINT MONO (-3690 4910);
FORCEPROP 0 LASTPIN (-3700 4850) $PN W7
J 0
(-3690 4860);
DISPLAY 0.489362 (-3690 4860);
PAINT MONO (-3690 4860);
FORCEPROP 0 LASTPIN (-3700 4800) $PN AA5
J 0
(-3690 4810);
DISPLAY 0.489362 (-3690 4810);
PAINT MONO (-3690 4810);
FORCEPROP 0 LASTPIN (-3700 4750) $PN AB7
J 0
(-3690 4760);
DISPLAY 0.489362 (-3690 4760);
PAINT MONO (-3690 4760);
FORCEPROP 0 LASTPIN (-3700 4700) $PN AB6
J 0
(-3690 4710);
DISPLAY 0.489362 (-3690 4710);
PAINT MONO (-3690 4710);
FORCEPROP 0 LASTPIN (-3700 4650) $PN AC7
J 0
(-3690 4660);
DISPLAY 0.489362 (-3690 4660);
PAINT MONO (-3690 4660);
FORCEPROP 0 LASTPIN (-3700 4550) $PN AC5
J 0
(-3690 4560);
DISPLAY 0.489362 (-3690 4560);
PAINT MONO (-3690 4560);
FORCEPROP 0 LASTPIN (-3700 4500) $PN AD7
J 0
(-3690 4510);
DISPLAY 0.489362 (-3690 4510);
PAINT MONO (-3690 4510);
FORCEPROP 0 LASTPIN (-3700 4450) $PN AD6
J 0
(-3690 4460);
DISPLAY 0.489362 (-3690 4460);
PAINT MONO (-3690 4460);
FORCEPROP 0 LASTPIN (-3700 4400) $PN AE7
J 0
(-3690 4410);
DISPLAY 0.489362 (-3690 4410);
PAINT MONO (-3690 4410);
FORCEPROP 0 LASTPIN (-3700 4350) $PN AG5
J 0
(-3690 4360);
DISPLAY 0.489362 (-3690 4360);
PAINT MONO (-3690 4360);
FORCEPROP 0 LASTPIN (-3700 4300) $PN AH7
J 0
(-3690 4310);
DISPLAY 0.489362 (-3690 4310);
PAINT MONO (-3690 4310);
FORCEPROP 0 LASTPIN (-3700 4250) $PN AH6
J 0
(-3690 4260);
DISPLAY 0.489362 (-3690 4260);
PAINT MONO (-3690 4260);
FORCEPROP 0 LASTPIN (-3700 4200) $PN AJ7
J 0
(-3690 4210);
DISPLAY 0.489362 (-3690 4210);
PAINT MONO (-3690 4210);
FORCEPROP 0 LASTPIN (-5300 5900) $PN G5
J 2
(-5310 5910);
DISPLAY 0.489362 (-5310 5910);
PAINT MONO (-5310 5910);
FORCEPROP 0 LASTPIN (-5300 5800) $PN N5
J 2
(-5310 5810);
DISPLAY 0.489362 (-5310 5810);
PAINT MONO (-5310 5810);
FORCEPROP 0 LASTPIN (-5300 5700) $PN W5
J 2
(-5310 5710);
DISPLAY 0.489362 (-5310 5710);
PAINT MONO (-5310 5710);
FORCEPROP 0 LASTPIN (-5300 5600) $PN AE5
J 2
(-5310 5610);
DISPLAY 0.489362 (-5310 5610);
PAINT MONO (-5310 5610);
FORCEPROP 0 LASTPIN (-5300 5500) $PN AL5
J 2
(-5310 5510);
DISPLAY 0.489362 (-5310 5510);
PAINT MONO (-5310 5510);
FORCEPROP 0 LASTPIN (-5300 5400) $PN J7
J 2
(-5310 5410);
DISPLAY 0.489362 (-5310 5410);
PAINT MONO (-5310 5410);
FORCEPROP 0 LASTPIN (-5300 5300) $PN R7
J 2
(-5310 5310);
DISPLAY 0.489362 (-5310 5310);
PAINT MONO (-5310 5310);
FORCEPROP 0 LASTPIN (-5300 5200) $PN AA7
J 2
(-5310 5210);
DISPLAY 0.489362 (-5310 5210);
PAINT MONO (-5310 5210);
FORCEPROP 0 LASTPIN (-5300 5100) $PN AG7
J 2
(-5310 5110);
DISPLAY 0.489362 (-5310 5110);
PAINT MONO (-5310 5110);
FORCEPROP 0 LASTPIN (-5300 5000) $PN AN7
J 2
(-5310 5010);
DISPLAY 0.489362 (-5310 5010);
PAINT MONO (-5310 5010);
FORCEPROP 0 LASTPIN (-5300 5850) $PN H6
J 2
(-5310 5860);
DISPLAY 0.489362 (-5310 5860);
PAINT MONO (-5310 5860);
FORCEPROP 0 LASTPIN (-5300 5750) $PN P6
J 2
(-5310 5760);
DISPLAY 0.489362 (-5310 5760);
PAINT MONO (-5310 5760);
FORCEPROP 0 LASTPIN (-5300 5650) $PN Y6
J 2
(-5310 5660);
DISPLAY 0.489362 (-5310 5660);
PAINT MONO (-5310 5660);
FORCEPROP 0 LASTPIN (-5300 5550) $PN AF6
J 2
(-5310 5560);
DISPLAY 0.489362 (-5310 5560);
PAINT MONO (-5310 5560);
FORCEPROP 0 LASTPIN (-5300 5450) $PN AM6
J 2
(-5310 5460);
DISPLAY 0.489362 (-5310 5460);
PAINT MONO (-5310 5460);
FORCEPROP 0 LASTPIN (-5300 5350) $PN H7
J 2
(-5310 5360);
DISPLAY 0.489362 (-5310 5360);
PAINT MONO (-5310 5360);
FORCEPROP 0 LASTPIN (-5300 5250) $PN P7
J 2
(-5310 5260);
DISPLAY 0.489362 (-5310 5260);
PAINT MONO (-5310 5260);
FORCEPROP 0 LASTPIN (-5300 5150) $PN Y7
J 2
(-5310 5160);
DISPLAY 0.489362 (-5310 5160);
PAINT MONO (-5310 5160);
FORCEPROP 0 LASTPIN (-5300 5050) $PN AF7
J 2
(-5310 5060);
DISPLAY 0.489362 (-5310 5060);
PAINT MONO (-5310 5060);
FORCEPROP 0 LASTPIN (-5300 4950) $PN AM7
J 2
(-5310 4960);
DISPLAY 0.489362 (-5310 4960);
PAINT MONO (-5310 4960);
FORCEPROP 0 LASTPIN (-5300 2500) $PN BC7
J 2
(-5310 2510);
DISPLAY 0.489362 (-5310 2510);
PAINT MONO (-5310 2510);
FORCEPROP 0 LASTPIN (-5300 2400) $PN BM7
J 2
(-5310 2410);
DISPLAY 0.489362 (-5310 2410);
PAINT MONO (-5310 2410);
FORCEPROP 0 LASTPIN (-5300 2350) $PN BN5
J 2
(-5310 2360);
DISPLAY 0.489362 (-5310 2360);
PAINT MONO (-5310 2360);
FORCEPROP 0 LASTPIN (-5300 2250) $PN BP6
J 2
(-5310 2260);
DISPLAY 0.489362 (-5310 2260);
PAINT MONO (-5310 2260);
FORCEPROP 0 LASTPIN (-5300 1350) $PN BL5
J 2
(-5310 1360);
DISPLAY 0.489362 (-5310 1360);
PAINT MONO (-5310 1360);
FORCEPROP 0 LASTPIN (-5300 1300) $PN BM6
J 2
(-5310 1310);
DISPLAY 0.489362 (-5310 1310);
PAINT MONO (-5310 1310);
FORCEPROP 0 LASTPIN (-5300 1200) $PN BR5
J 2
(-5310 1210);
DISPLAY 0.489362 (-5310 1210);
PAINT MONO (-5310 1210);
FORCEPROP 0 LASTPIN (-5300 3350) $PN BG7
J 2
(-5310 3360);
DISPLAY 0.489362 (-5310 3360);
PAINT MONO (-5310 3360);
FORCEPROP 0 LASTPIN (-5300 3300) $PN BH7
J 2
(-5310 3310);
DISPLAY 0.489362 (-5310 3310);
PAINT MONO (-5310 3310);
FORCEPROP 0 LASTPIN (-5300 3250) $PN BH6
J 2
(-5310 3260);
DISPLAY 0.489362 (-5310 3260);
PAINT MONO (-5310 3260);
FORCEPROP 0 LASTPIN (-5300 3200) $PN BJ5
J 2
(-5310 3210);
DISPLAY 0.489362 (-5310 3210);
PAINT MONO (-5310 3210);
FORCEPROP 0 LASTPIN (-5300 3150) $PN BJ7
J 2
(-5310 3160);
DISPLAY 0.489362 (-5310 3160);
PAINT MONO (-5310 3160);
FORCEPROP 0 LASTPIN (-5300 3100) $PN BK7
J 2
(-5310 3110);
DISPLAY 0.489362 (-5310 3110);
PAINT MONO (-5310 3110);
FORCEPROP 0 LASTPIN (-5300 3050) $PN BK6
J 2
(-5310 3060);
DISPLAY 0.489362 (-5310 3060);
PAINT MONO (-5310 3060);
FORCEPROP 0 LASTPIN (-3700 1850) $PN BY6
J 0
(-3690 1860);
DISPLAY 0.489362 (-3690 1860);
PAINT MONO (-3690 1860);
FORCEPROP 0 LASTPIN (-3700 1800) $PN CA7
J 0
(-3690 1810);
DISPLAY 0.489362 (-3690 1810);
PAINT MONO (-3690 1810);
FORCEPROP 0 LASTPIN (-3700 1750) $PN CA5
J 0
(-3690 1760);
DISPLAY 0.489362 (-3690 1760);
PAINT MONO (-3690 1760);
FORCEPROP 0 LASTPIN (-3700 1700) $PN CB7
J 0
(-3690 1710);
DISPLAY 0.489362 (-3690 1710);
PAINT MONO (-3690 1710);
FORCEPROP 0 LASTPIN (-3700 1650) $PN BT6
J 0
(-3690 1660);
DISPLAY 0.489362 (-3690 1660);
PAINT MONO (-3690 1660);
FORCEPROP 0 LASTPIN (-3700 1600) $PN BU7
J 0
(-3690 1610);
DISPLAY 0.489362 (-3690 1610);
PAINT MONO (-3690 1610);
FORCEPROP 0 LASTPIN (-3700 1550) $PN BU5
J 0
(-3690 1560);
DISPLAY 0.489362 (-3690 1560);
PAINT MONO (-3690 1560);
FORCEPROP 0 LASTPIN (-3700 1500) $PN BV7
J 0
(-3690 1510);
DISPLAY 0.489362 (-3690 1510);
PAINT MONO (-3690 1510);
FORCEPROP 0 LASTPIN (-3700 4100) $PN CB6
J 0
(-3690 4110);
DISPLAY 0.489362 (-3690 4110);
PAINT MONO (-3690 4110);
FORCEPROP 0 LASTPIN (-3700 4050) $PN CC7
J 0
(-3690 4060);
DISPLAY 0.489362 (-3690 4060);
PAINT MONO (-3690 4060);
FORCEPROP 0 LASTPIN (-3700 4000) $PN CC5
J 0
(-3690 4010);
DISPLAY 0.489362 (-3690 4010);
PAINT MONO (-3690 4010);
FORCEPROP 0 LASTPIN (-3700 3950) $PN CD7
J 0
(-3690 3960);
DISPLAY 0.489362 (-3690 3960);
PAINT MONO (-3690 3960);
FORCEPROP 0 LASTPIN (-3700 3900) $PN CF6
J 0
(-3690 3910);
DISPLAY 0.489362 (-3690 3910);
PAINT MONO (-3690 3910);
FORCEPROP 0 LASTPIN (-3700 3850) $PN CG7
J 0
(-3690 3860);
DISPLAY 0.489362 (-3690 3860);
PAINT MONO (-3690 3860);
FORCEPROP 0 LASTPIN (-3700 3800) $PN CG5
J 0
(-3690 3810);
DISPLAY 0.489362 (-3690 3810);
PAINT MONO (-3690 3810);
FORCEPROP 0 LASTPIN (-3700 3750) $PN CH7
J 0
(-3690 3760);
DISPLAY 0.489362 (-3690 3760);
PAINT MONO (-3690 3760);
FORCEPROP 0 LASTPIN (-3700 3650) $PN CH6
J 0
(-3690 3660);
DISPLAY 0.489362 (-3690 3660);
PAINT MONO (-3690 3660);
FORCEPROP 0 LASTPIN (-3700 3600) $PN CJ7
J 0
(-3690 3610);
DISPLAY 0.489362 (-3690 3610);
PAINT MONO (-3690 3610);
FORCEPROP 0 LASTPIN (-3700 3550) $PN CJ5
J 0
(-3690 3560);
DISPLAY 0.489362 (-3690 3560);
PAINT MONO (-3690 3560);
FORCEPROP 0 LASTPIN (-3700 3500) $PN CK7
J 0
(-3690 3510);
DISPLAY 0.489362 (-3690 3510);
PAINT MONO (-3690 3510);
FORCEPROP 0 LASTPIN (-3700 3450) $PN CM6
J 0
(-3690 3460);
DISPLAY 0.489362 (-3690 3460);
PAINT MONO (-3690 3460);
FORCEPROP 0 LASTPIN (-3700 3400) $PN CN7
J 0
(-3690 3410);
DISPLAY 0.489362 (-3690 3410);
PAINT MONO (-3690 3410);
FORCEPROP 0 LASTPIN (-3700 3350) $PN CN5
J 0
(-3690 3360);
DISPLAY 0.489362 (-3690 3360);
PAINT MONO (-3690 3360);
FORCEPROP 0 LASTPIN (-3700 3300) $PN CP7
J 0
(-3690 3310);
DISPLAY 0.489362 (-3690 3310);
PAINT MONO (-3690 3310);
FORCEPROP 0 LASTPIN (-3700 3200) $PN CP6
J 0
(-3690 3210);
DISPLAY 0.489362 (-3690 3210);
PAINT MONO (-3690 3210);
FORCEPROP 0 LASTPIN (-3700 3150) $PN CR7
J 0
(-3690 3160);
DISPLAY 0.489362 (-3690 3160);
PAINT MONO (-3690 3160);
FORCEPROP 0 LASTPIN (-3700 3100) $PN CR5
J 0
(-3690 3110);
DISPLAY 0.489362 (-3690 3110);
PAINT MONO (-3690 3110);
FORCEPROP 0 LASTPIN (-3700 3050) $PN CT7
J 0
(-3690 3060);
DISPLAY 0.489362 (-3690 3060);
PAINT MONO (-3690 3060);
FORCEPROP 0 LASTPIN (-3700 3000) $PN CV6
J 0
(-3690 3010);
DISPLAY 0.489362 (-3690 3010);
PAINT MONO (-3690 3010);
FORCEPROP 0 LASTPIN (-3700 2950) $PN CW7
J 0
(-3690 2960);
DISPLAY 0.489362 (-3690 2960);
PAINT MONO (-3690 2960);
FORCEPROP 0 LASTPIN (-3700 2900) $PN CW5
J 0
(-3690 2910);
DISPLAY 0.489362 (-3690 2910);
PAINT MONO (-3690 2910);
FORCEPROP 0 LASTPIN (-3700 2850) $PN CY7
J 0
(-3690 2860);
DISPLAY 0.489362 (-3690 2860);
PAINT MONO (-3690 2860);
FORCEPROP 0 LASTPIN (-3700 2750) $PN CY6
J 0
(-3690 2760);
DISPLAY 0.489362 (-3690 2760);
PAINT MONO (-3690 2760);
FORCEPROP 0 LASTPIN (-3700 2700) $PN DA7
J 0
(-3690 2710);
DISPLAY 0.489362 (-3690 2710);
PAINT MONO (-3690 2710);
FORCEPROP 0 LASTPIN (-3700 2650) $PN DA5
J 0
(-3690 2660);
DISPLAY 0.489362 (-3690 2660);
PAINT MONO (-3690 2660);
FORCEPROP 0 LASTPIN (-3700 2600) $PN DB7
J 0
(-3690 2610);
DISPLAY 0.489362 (-3690 2610);
PAINT MONO (-3690 2610);
FORCEPROP 0 LASTPIN (-3700 2550) $PN DD6
J 0
(-3690 2560);
DISPLAY 0.489362 (-3690 2560);
PAINT MONO (-3690 2560);
FORCEPROP 0 LASTPIN (-3700 2500) $PN DE7
J 0
(-3690 2510);
DISPLAY 0.489362 (-3690 2510);
PAINT MONO (-3690 2510);
FORCEPROP 0 LASTPIN (-3700 2450) $PN DE5
J 0
(-3690 2460);
DISPLAY 0.489362 (-3690 2460);
PAINT MONO (-3690 2460);
FORCEPROP 0 LASTPIN (-3700 2400) $PN DF7
J 0
(-3690 2410);
DISPLAY 0.489362 (-3690 2410);
PAINT MONO (-3690 2410);
FORCEPROP 0 LASTPIN (-5300 4850) $PN CD6
J 2
(-5310 4860);
DISPLAY 0.489362 (-5310 4860);
PAINT MONO (-5310 4860);
FORCEPROP 0 LASTPIN (-5300 4750) $PN CK6
J 2
(-5310 4760);
DISPLAY 0.489362 (-5310 4760);
PAINT MONO (-5310 4760);
FORCEPROP 0 LASTPIN (-5300 4650) $PN CT6
J 2
(-5310 4660);
DISPLAY 0.489362 (-5310 4660);
PAINT MONO (-5310 4660);
FORCEPROP 0 LASTPIN (-5300 4550) $PN DB6
J 2
(-5310 4560);
DISPLAY 0.489362 (-5310 4560);
PAINT MONO (-5310 4560);
FORCEPROP 0 LASTPIN (-5300 4450) $PN BY7
J 2
(-5310 4460);
DISPLAY 0.489362 (-5310 4460);
PAINT MONO (-5310 4460);
FORCEPROP 0 LASTPIN (-5300 4350) $PN CF7
J 2
(-5310 4360);
DISPLAY 0.489362 (-5310 4360);
PAINT MONO (-5310 4360);
FORCEPROP 0 LASTPIN (-5300 4250) $PN CM7
J 2
(-5310 4260);
DISPLAY 0.489362 (-5310 4260);
PAINT MONO (-5310 4260);
FORCEPROP 0 LASTPIN (-5300 4150) $PN CV7
J 2
(-5310 4160);
DISPLAY 0.489362 (-5310 4160);
PAINT MONO (-5310 4160);
FORCEPROP 0 LASTPIN (-5300 4050) $PN DD7
J 2
(-5310 4060);
DISPLAY 0.489362 (-5310 4060);
PAINT MONO (-5310 4060);
FORCEPROP 0 LASTPIN (-5300 3950) $PN BV6
J 2
(-5310 3960);
DISPLAY 0.489362 (-5310 3960);
PAINT MONO (-5310 3960);
FORCEPROP 0 LASTPIN (-5300 4800) $PN CE5
J 2
(-5310 4810);
DISPLAY 0.489362 (-5310 4810);
PAINT MONO (-5310 4810);
FORCEPROP 0 LASTPIN (-5300 4700) $PN CL5
J 2
(-5310 4710);
DISPLAY 0.489362 (-5310 4710);
PAINT MONO (-5310 4710);
FORCEPROP 0 LASTPIN (-5300 4600) $PN CU5
J 2
(-5310 4610);
DISPLAY 0.489362 (-5310 4610);
PAINT MONO (-5310 4610);
FORCEPROP 0 LASTPIN (-5300 4500) $PN DC5
J 2
(-5310 4510);
DISPLAY 0.489362 (-5310 4510);
PAINT MONO (-5310 4510);
FORCEPROP 0 LASTPIN (-5300 4400) $PN BW7
J 2
(-5310 4410);
DISPLAY 0.489362 (-5310 4410);
PAINT MONO (-5310 4410);
FORCEPROP 0 LASTPIN (-5300 4300) $PN CE7
J 2
(-5310 4310);
DISPLAY 0.489362 (-5310 4310);
PAINT MONO (-5310 4310);
FORCEPROP 0 LASTPIN (-5300 4200) $PN CL7
J 2
(-5310 4210);
DISPLAY 0.489362 (-5310 4210);
PAINT MONO (-5310 4210);
FORCEPROP 0 LASTPIN (-5300 4100) $PN CU7
J 2
(-5310 4110);
DISPLAY 0.489362 (-5310 4110);
PAINT MONO (-5310 4110);
FORCEPROP 0 LASTPIN (-5300 4000) $PN DC7
J 2
(-5310 4010);
DISPLAY 0.489362 (-5310 4010);
PAINT MONO (-5310 4010);
FORCEPROP 0 LASTPIN (-5300 3900) $PN BW5
J 2
(-5310 3910);
DISPLAY 0.489362 (-5310 3910);
PAINT MONO (-5310 3910);
FORCEPROP 0 LASTPIN (-5300 2150) $PN BL7
J 2
(-5310 2160);
DISPLAY 0.489362 (-5310 2160);
PAINT MONO (-5310 2160);
FORCEPROP 0 LASTPIN (-5300 1100) $PN BF7
J 2
(-5310 1110);
DISPLAY 0.489362 (-5310 1110);
PAINT MONO (-5310 1110);
FORCEPROP 2 LAST PART_TYPE SMLF
J 0
(-5150 6300);
DISPLAY 1.021277 (-5150 6300);
FORCEPROP 1 LAST MATERIAL IO
J 0
(-5145 6082);
DISPLAY 0.489362 (-5145 6082);
PAINT SKYBLUE (-5145 6082);
FORCEPROP 2 LAST VALUE SOCKET6096_13568-001
J 0
(-5150 6200);
DISPLAY 0.489362 (-5150 6200);
PAINT SKYBLUE (-5150 6200);
FORCEPROP 2 LAST CDS_LIB pure_quanta
J 0
(-4500 3525);
DISPLAY INVISIBLE (-4500 3525);
FORCEPROP 1 LAST CDS_LMAN_SYM_OUTLINE -650,2525,650,-2525
J 0
(-4500 3525);
DISPLAY 0.468085 (-4500 3525);
PAINT GREEN (-4500 3525);
DISPLAY INVISIBLE (-4500 3525);
FORCEPROP 1 LAST NEEDS_NO_SIZE TRUE
J 0
(-4500 3525);
DISPLAY 0.723404 (-4500 3525);
PAINT GREEN (-4500 3525);
DISPLAY INVISIBLE (-4500 3525);
FORCEPROP 1 LAST PATH I159
J 0
(-4500 3525);
DISPLAY 0.723404 (-4500 3525);
PAINT GREEN (-4500 3525);
DISPLAY INVISIBLE (-4500 3525);
FORCEPROP 1 LAST PART_NUMBER DGA^6000030
J 0
(-5145 6209);
DISPLAY 0.489362 (-5145 6209);
PAINT SKYBLUE (-5145 6209);
DISPLAY INVISIBLE (-5145 6209);
FORCEADD OFFPAGE..3
(-2500 5925);
FORCEPROP 2 LAST $XR0 108 
J 0
(-2286 5925);
DISPLAY 0.638298 (-2286 5925);
PAINT MONO (-2286 5925);
FORCEPROP 2 LAST CDS_LIB mstr_standard
J 0
(-2500 5925);
DISPLAY 0.723404 (-2500 5925);
PAINT MONO (-2500 5925);
DISPLAY INVISIBLE (-2500 5925);
FORCEPROP 1 LAST OFFPAGE TRUE
J 0
(-2175 5800);
DISPLAY 0.872340 (-2175 5800);
PAINT GREEN (-2175 5800);
DISPLAY INVISIBLE (-2175 5800);
FORCEPROP 1 LAST COMMENT_BODY TRUE
J 0
(-2550 5825);
DISPLAY 0.872340 (-2550 5825);
PAINT GREEN (-2550 5825);
DISPLAY INVISIBLE (-2550 5825);
FORCEPROP 2 LAST PATH I160
J 0
(-2275 5975);
DISPLAY 1.021277 (-2275 5975);
DISPLAY INVISIBLE (-2275 5975);
FORCEADD TAP..1
(-3225 5900);
FORCEPROP 3 LASTPIN (-3275 5900) SIG_NAME M_K_CPU1_SA_DQ<0>
J 0
(-3265 5910);
DISPLAY 0.659574 (-3265 5910);
PAINT MONO (-3265 5910);
DISPLAY INVISIBLE (-3265 5910);
FORCEPROP 1 LASTPIN (-3275 5900) BN 0
J 0
(-3287 5908);
DISPLAY 0.489362 (-3287 5908);
PAINT GREEN (-3287 5908);
FORCEPROP 2 LAST CDS_LIB mstr_standard
J 0
(-3225 5900);
DISPLAY 0.723404 (-3225 5900);
PAINT MONO (-3225 5900);
DISPLAY INVISIBLE (-3225 5900);
FORCEPROP 1 LAST BODY_TYPE PLUMBING
J 0
(-3225 5950);
DISPLAY 0.872340 (-3225 5950);
PAINT GREEN (-3225 5950);
DISPLAY INVISIBLE (-3225 5950);
FORCEPROP 1 LAST HDL_TAP TRUE
J 0
(-2900 5775);
DISPLAY 0.872340 (-2900 5775);
DISPLAY INVISIBLE (-2900 5775);
FORCEPROP 1 LAST PATH I161
J 0
(-3227 5900);
DISPLAY 0.872340 (-3227 5900);
PAINT GREEN (-3227 5900);
DISPLAY INVISIBLE (-3227 5900);
FORCEADD TAP..1
(-3225 5850);
FORCEPROP 3 LASTPIN (-3275 5850) SIG_NAME M_K_CPU1_SA_DQ<1>
J 0
(-3265 5860);
DISPLAY 0.659574 (-3265 5860);
PAINT MONO (-3265 5860);
DISPLAY INVISIBLE (-3265 5860);
FORCEPROP 1 LASTPIN (-3275 5850) BN 1
J 0
(-3287 5858);
DISPLAY 0.489362 (-3287 5858);
PAINT GREEN (-3287 5858);
FORCEPROP 2 LAST CDS_LIB mstr_standard
J 0
(-3225 5850);
DISPLAY 0.723404 (-3225 5850);
PAINT MONO (-3225 5850);
DISPLAY INVISIBLE (-3225 5850);
FORCEPROP 1 LAST BODY_TYPE PLUMBING
J 0
(-3225 5900);
DISPLAY 0.872340 (-3225 5900);
PAINT GREEN (-3225 5900);
DISPLAY INVISIBLE (-3225 5900);
FORCEPROP 1 LAST HDL_TAP TRUE
J 0
(-2900 5725);
DISPLAY 0.872340 (-2900 5725);
DISPLAY INVISIBLE (-2900 5725);
FORCEPROP 1 LAST PATH I162
J 0
(-3227 5850);
DISPLAY 0.872340 (-3227 5850);
PAINT GREEN (-3227 5850);
DISPLAY INVISIBLE (-3227 5850);
FORCEADD TAP..1
(-3225 5800);
FORCEPROP 3 LASTPIN (-3275 5800) SIG_NAME M_K_CPU1_SA_DQ<2>
J 0
(-3265 5810);
DISPLAY 0.659574 (-3265 5810);
PAINT MONO (-3265 5810);
DISPLAY INVISIBLE (-3265 5810);
FORCEPROP 1 LASTPIN (-3275 5800) BN 2
J 0
(-3287 5808);
DISPLAY 0.489362 (-3287 5808);
PAINT GREEN (-3287 5808);
FORCEPROP 2 LAST CDS_LIB mstr_standard
J 0
(-3225 5800);
DISPLAY 0.723404 (-3225 5800);
PAINT MONO (-3225 5800);
DISPLAY INVISIBLE (-3225 5800);
FORCEPROP 1 LAST BODY_TYPE PLUMBING
J 0
(-3225 5850);
DISPLAY 0.872340 (-3225 5850);
PAINT GREEN (-3225 5850);
DISPLAY INVISIBLE (-3225 5850);
FORCEPROP 1 LAST HDL_TAP TRUE
J 0
(-2900 5675);
DISPLAY 0.872340 (-2900 5675);
DISPLAY INVISIBLE (-2900 5675);
FORCEPROP 1 LAST PATH I163
J 0
(-3227 5800);
DISPLAY 0.872340 (-3227 5800);
PAINT GREEN (-3227 5800);
DISPLAY INVISIBLE (-3227 5800);
FORCEADD TAP..1
(-3225 5750);
FORCEPROP 3 LASTPIN (-3275 5750) SIG_NAME M_K_CPU1_SA_DQ<3>
J 0
(-3265 5760);
DISPLAY 0.659574 (-3265 5760);
PAINT MONO (-3265 5760);
DISPLAY INVISIBLE (-3265 5760);
FORCEPROP 1 LASTPIN (-3275 5750) BN 3
J 0
(-3287 5758);
DISPLAY 0.489362 (-3287 5758);
PAINT GREEN (-3287 5758);
FORCEPROP 2 LAST CDS_LIB mstr_standard
J 0
(-3225 5750);
DISPLAY 0.723404 (-3225 5750);
PAINT MONO (-3225 5750);
DISPLAY INVISIBLE (-3225 5750);
FORCEPROP 1 LAST BODY_TYPE PLUMBING
J 0
(-3225 5800);
DISPLAY 0.872340 (-3225 5800);
PAINT GREEN (-3225 5800);
DISPLAY INVISIBLE (-3225 5800);
FORCEPROP 1 LAST HDL_TAP TRUE
J 0
(-2900 5625);
DISPLAY 0.872340 (-2900 5625);
DISPLAY INVISIBLE (-2900 5625);
FORCEPROP 1 LAST PATH I164
J 0
(-3227 5750);
DISPLAY 0.872340 (-3227 5750);
PAINT GREEN (-3227 5750);
DISPLAY INVISIBLE (-3227 5750);
FORCEADD TAP..1
(-3225 5650);
FORCEPROP 3 LASTPIN (-3275 5650) SIG_NAME M_K_CPU1_SA_DQ<5>
J 0
(-3265 5660);
DISPLAY 0.659574 (-3265 5660);
PAINT MONO (-3265 5660);
DISPLAY INVISIBLE (-3265 5660);
FORCEPROP 1 LASTPIN (-3275 5650) BN 5
J 0
(-3287 5658);
DISPLAY 0.489362 (-3287 5658);
PAINT GREEN (-3287 5658);
FORCEPROP 2 LAST CDS_LIB mstr_standard
J 0
(-3225 5650);
DISPLAY 0.723404 (-3225 5650);
PAINT MONO (-3225 5650);
DISPLAY INVISIBLE (-3225 5650);
FORCEPROP 1 LAST BODY_TYPE PLUMBING
J 0
(-3225 5700);
DISPLAY 0.872340 (-3225 5700);
PAINT GREEN (-3225 5700);
DISPLAY INVISIBLE (-3225 5700);
FORCEPROP 1 LAST HDL_TAP TRUE
J 0
(-2900 5525);
DISPLAY 0.872340 (-2900 5525);
DISPLAY INVISIBLE (-2900 5525);
FORCEPROP 1 LAST PATH I165
J 0
(-3227 5650);
DISPLAY 0.872340 (-3227 5650);
PAINT GREEN (-3227 5650);
DISPLAY INVISIBLE (-3227 5650);
FORCEADD TAP..1
(-3225 5700);
FORCEPROP 3 LASTPIN (-3275 5700) SIG_NAME M_K_CPU1_SA_DQ<4>
J 0
(-3265 5710);
DISPLAY 0.659574 (-3265 5710);
PAINT MONO (-3265 5710);
DISPLAY INVISIBLE (-3265 5710);
FORCEPROP 1 LASTPIN (-3275 5700) BN 4
J 0
(-3287 5708);
DISPLAY 0.489362 (-3287 5708);
PAINT GREEN (-3287 5708);
FORCEPROP 2 LAST CDS_LIB mstr_standard
J 0
(-3225 5700);
DISPLAY 0.723404 (-3225 5700);
PAINT MONO (-3225 5700);
DISPLAY INVISIBLE (-3225 5700);
FORCEPROP 1 LAST BODY_TYPE PLUMBING
J 0
(-3225 5750);
DISPLAY 0.872340 (-3225 5750);
PAINT GREEN (-3225 5750);
DISPLAY INVISIBLE (-3225 5750);
FORCEPROP 1 LAST HDL_TAP TRUE
J 0
(-2900 5575);
DISPLAY 0.872340 (-2900 5575);
DISPLAY INVISIBLE (-2900 5575);
FORCEPROP 1 LAST PATH I166
J 0
(-3227 5700);
DISPLAY 0.872340 (-3227 5700);
PAINT GREEN (-3227 5700);
DISPLAY INVISIBLE (-3227 5700);
FORCEADD TAP..1
(-3225 5600);
FORCEPROP 3 LASTPIN (-3275 5600) SIG_NAME M_K_CPU1_SA_DQ<6>
J 0
(-3265 5610);
DISPLAY 0.659574 (-3265 5610);
PAINT MONO (-3265 5610);
DISPLAY INVISIBLE (-3265 5610);
FORCEPROP 1 LASTPIN (-3275 5600) BN 6
J 0
(-3287 5608);
DISPLAY 0.489362 (-3287 5608);
PAINT GREEN (-3287 5608);
FORCEPROP 2 LAST CDS_LIB mstr_standard
J 0
(-3225 5600);
DISPLAY 0.723404 (-3225 5600);
PAINT MONO (-3225 5600);
DISPLAY INVISIBLE (-3225 5600);
FORCEPROP 1 LAST BODY_TYPE PLUMBING
J 0
(-3225 5650);
DISPLAY 0.872340 (-3225 5650);
PAINT GREEN (-3225 5650);
DISPLAY INVISIBLE (-3225 5650);
FORCEPROP 1 LAST HDL_TAP TRUE
J 0
(-2900 5475);
DISPLAY 0.872340 (-2900 5475);
DISPLAY INVISIBLE (-2900 5475);
FORCEPROP 1 LAST PATH I167
J 0
(-3227 5600);
DISPLAY 0.872340 (-3227 5600);
PAINT GREEN (-3227 5600);
DISPLAY INVISIBLE (-3227 5600);
FORCEADD TAP..1
(-3225 5550);
FORCEPROP 3 LASTPIN (-3275 5550) SIG_NAME M_K_CPU1_SA_DQ<7>
J 0
(-3265 5560);
DISPLAY 0.659574 (-3265 5560);
PAINT MONO (-3265 5560);
DISPLAY INVISIBLE (-3265 5560);
FORCEPROP 1 LASTPIN (-3275 5550) BN 7
J 0
(-3287 5558);
DISPLAY 0.489362 (-3287 5558);
PAINT GREEN (-3287 5558);
FORCEPROP 2 LAST CDS_LIB mstr_standard
J 0
(-3225 5550);
DISPLAY 0.723404 (-3225 5550);
PAINT MONO (-3225 5550);
DISPLAY INVISIBLE (-3225 5550);
FORCEPROP 1 LAST BODY_TYPE PLUMBING
J 0
(-3225 5600);
DISPLAY 0.872340 (-3225 5600);
PAINT GREEN (-3225 5600);
DISPLAY INVISIBLE (-3225 5600);
FORCEPROP 1 LAST HDL_TAP TRUE
J 0
(-2900 5425);
DISPLAY 0.872340 (-2900 5425);
DISPLAY INVISIBLE (-2900 5425);
FORCEPROP 1 LAST PATH I168
J 0
(-3227 5550);
DISPLAY 0.872340 (-3227 5550);
PAINT GREEN (-3227 5550);
DISPLAY INVISIBLE (-3227 5550);
FORCEADD TAP..1
(-3225 5400);
FORCEPROP 3 LASTPIN (-3275 5400) SIG_NAME M_K_CPU1_SA_DQ<9>
J 0
(-3265 5410);
DISPLAY 0.659574 (-3265 5410);
PAINT MONO (-3265 5410);
DISPLAY INVISIBLE (-3265 5410);
FORCEPROP 1 LASTPIN (-3275 5400) BN 9
J 0
(-3287 5408);
DISPLAY 0.489362 (-3287 5408);
PAINT GREEN (-3287 5408);
FORCEPROP 2 LAST CDS_LIB mstr_standard
J 0
(-3225 5400);
DISPLAY 0.723404 (-3225 5400);
PAINT MONO (-3225 5400);
DISPLAY INVISIBLE (-3225 5400);
FORCEPROP 1 LAST BODY_TYPE PLUMBING
J 0
(-3225 5450);
DISPLAY 0.872340 (-3225 5450);
PAINT GREEN (-3225 5450);
DISPLAY INVISIBLE (-3225 5450);
FORCEPROP 1 LAST HDL_TAP TRUE
J 0
(-2900 5275);
DISPLAY 0.872340 (-2900 5275);
DISPLAY INVISIBLE (-2900 5275);
FORCEPROP 1 LAST PATH I169
J 0
(-3227 5400);
DISPLAY 0.872340 (-3227 5400);
PAINT GREEN (-3227 5400);
DISPLAY INVISIBLE (-3227 5400);
FORCEADD TAP..1
(-3225 5450);
FORCEPROP 3 LASTPIN (-3275 5450) SIG_NAME M_K_CPU1_SA_DQ<8>
J 0
(-3265 5460);
DISPLAY 0.659574 (-3265 5460);
PAINT MONO (-3265 5460);
DISPLAY INVISIBLE (-3265 5460);
FORCEPROP 1 LASTPIN (-3275 5450) BN 8
J 0
(-3287 5458);
DISPLAY 0.489362 (-3287 5458);
PAINT GREEN (-3287 5458);
FORCEPROP 2 LAST CDS_LIB mstr_standard
J 0
(-3225 5450);
DISPLAY 0.723404 (-3225 5450);
PAINT MONO (-3225 5450);
DISPLAY INVISIBLE (-3225 5450);
FORCEPROP 1 LAST BODY_TYPE PLUMBING
J 0
(-3225 5500);
DISPLAY 0.872340 (-3225 5500);
PAINT GREEN (-3225 5500);
DISPLAY INVISIBLE (-3225 5500);
FORCEPROP 1 LAST HDL_TAP TRUE
J 0
(-2900 5325);
DISPLAY 0.872340 (-2900 5325);
DISPLAY INVISIBLE (-2900 5325);
FORCEPROP 1 LAST PATH I170
J 0
(-3227 5450);
DISPLAY 0.872340 (-3227 5450);
PAINT GREEN (-3227 5450);
DISPLAY INVISIBLE (-3227 5450);
FORCEADD TAP..1
(-3225 5350);
FORCEPROP 3 LASTPIN (-3275 5350) SIG_NAME M_K_CPU1_SA_DQ<10>
J 0
(-3265 5360);
DISPLAY 0.659574 (-3265 5360);
PAINT MONO (-3265 5360);
DISPLAY INVISIBLE (-3265 5360);
FORCEPROP 1 LASTPIN (-3275 5350) BN 10
J 0
(-3287 5358);
DISPLAY 0.489362 (-3287 5358);
PAINT GREEN (-3287 5358);
FORCEPROP 2 LAST CDS_LIB mstr_standard
J 0
(-3225 5350);
DISPLAY 0.723404 (-3225 5350);
PAINT MONO (-3225 5350);
DISPLAY INVISIBLE (-3225 5350);
FORCEPROP 1 LAST BODY_TYPE PLUMBING
J 0
(-3225 5400);
DISPLAY 0.872340 (-3225 5400);
PAINT GREEN (-3225 5400);
DISPLAY INVISIBLE (-3225 5400);
FORCEPROP 1 LAST HDL_TAP TRUE
J 0
(-2900 5225);
DISPLAY 0.872340 (-2900 5225);
DISPLAY INVISIBLE (-2900 5225);
FORCEPROP 1 LAST PATH I171
J 0
(-3227 5350);
DISPLAY 0.872340 (-3227 5350);
PAINT GREEN (-3227 5350);
DISPLAY INVISIBLE (-3227 5350);
FORCEADD TAP..1
(-3225 5300);
FORCEPROP 3 LASTPIN (-3275 5300) SIG_NAME M_K_CPU1_SA_DQ<11>
J 0
(-3265 5310);
DISPLAY 0.659574 (-3265 5310);
PAINT MONO (-3265 5310);
DISPLAY INVISIBLE (-3265 5310);
FORCEPROP 1 LASTPIN (-3275 5300) BN 11
J 0
(-3287 5308);
DISPLAY 0.489362 (-3287 5308);
PAINT GREEN (-3287 5308);
FORCEPROP 2 LAST CDS_LIB mstr_standard
J 0
(-3225 5300);
DISPLAY 0.723404 (-3225 5300);
PAINT MONO (-3225 5300);
DISPLAY INVISIBLE (-3225 5300);
FORCEPROP 1 LAST BODY_TYPE PLUMBING
J 0
(-3225 5350);
DISPLAY 0.872340 (-3225 5350);
PAINT GREEN (-3225 5350);
DISPLAY INVISIBLE (-3225 5350);
FORCEPROP 1 LAST HDL_TAP TRUE
J 0
(-2900 5175);
DISPLAY 0.872340 (-2900 5175);
DISPLAY INVISIBLE (-2900 5175);
FORCEPROP 1 LAST PATH I172
J 0
(-3227 5300);
DISPLAY 0.872340 (-3227 5300);
PAINT GREEN (-3227 5300);
DISPLAY INVISIBLE (-3227 5300);
FORCEADD TAP..1
(-3225 5250);
FORCEPROP 3 LASTPIN (-3275 5250) SIG_NAME M_K_CPU1_SA_DQ<12>
J 0
(-3265 5260);
DISPLAY 0.659574 (-3265 5260);
PAINT MONO (-3265 5260);
DISPLAY INVISIBLE (-3265 5260);
FORCEPROP 1 LASTPIN (-3275 5250) BN 12
J 0
(-3287 5258);
DISPLAY 0.489362 (-3287 5258);
PAINT GREEN (-3287 5258);
FORCEPROP 2 LAST CDS_LIB mstr_standard
J 0
(-3225 5250);
DISPLAY 0.723404 (-3225 5250);
PAINT MONO (-3225 5250);
DISPLAY INVISIBLE (-3225 5250);
FORCEPROP 1 LAST BODY_TYPE PLUMBING
J 0
(-3225 5300);
DISPLAY 0.872340 (-3225 5300);
PAINT GREEN (-3225 5300);
DISPLAY INVISIBLE (-3225 5300);
FORCEPROP 1 LAST HDL_TAP TRUE
J 0
(-2900 5125);
DISPLAY 0.872340 (-2900 5125);
DISPLAY INVISIBLE (-2900 5125);
FORCEPROP 1 LAST PATH I173
J 0
(-3227 5250);
DISPLAY 0.872340 (-3227 5250);
PAINT GREEN (-3227 5250);
DISPLAY INVISIBLE (-3227 5250);
FORCEADD TAP..1
(-3225 5200);
FORCEPROP 3 LASTPIN (-3275 5200) SIG_NAME M_K_CPU1_SA_DQ<13>
J 0
(-3265 5210);
DISPLAY 0.659574 (-3265 5210);
PAINT MONO (-3265 5210);
DISPLAY INVISIBLE (-3265 5210);
FORCEPROP 1 LASTPIN (-3275 5200) BN 13
J 0
(-3287 5208);
DISPLAY 0.489362 (-3287 5208);
PAINT GREEN (-3287 5208);
FORCEPROP 2 LAST CDS_LIB mstr_standard
J 0
(-3225 5200);
DISPLAY 0.723404 (-3225 5200);
PAINT MONO (-3225 5200);
DISPLAY INVISIBLE (-3225 5200);
FORCEPROP 1 LAST BODY_TYPE PLUMBING
J 0
(-3225 5250);
DISPLAY 0.872340 (-3225 5250);
PAINT GREEN (-3225 5250);
DISPLAY INVISIBLE (-3225 5250);
FORCEPROP 1 LAST HDL_TAP TRUE
J 0
(-2900 5075);
DISPLAY 0.872340 (-2900 5075);
DISPLAY INVISIBLE (-2900 5075);
FORCEPROP 1 LAST PATH I174
J 0
(-3227 5200);
DISPLAY 0.872340 (-3227 5200);
PAINT GREEN (-3227 5200);
DISPLAY INVISIBLE (-3227 5200);
FORCEADD TAP..1
(-3225 5150);
FORCEPROP 3 LASTPIN (-3275 5150) SIG_NAME M_K_CPU1_SA_DQ<14>
J 0
(-3265 5160);
DISPLAY 0.659574 (-3265 5160);
PAINT MONO (-3265 5160);
DISPLAY INVISIBLE (-3265 5160);
FORCEPROP 1 LASTPIN (-3275 5150) BN 14
J 0
(-3287 5158);
DISPLAY 0.489362 (-3287 5158);
PAINT GREEN (-3287 5158);
FORCEPROP 2 LAST CDS_LIB mstr_standard
J 0
(-3225 5150);
DISPLAY 0.723404 (-3225 5150);
PAINT MONO (-3225 5150);
DISPLAY INVISIBLE (-3225 5150);
FORCEPROP 1 LAST BODY_TYPE PLUMBING
J 0
(-3225 5200);
DISPLAY 0.872340 (-3225 5200);
PAINT GREEN (-3225 5200);
DISPLAY INVISIBLE (-3225 5200);
FORCEPROP 1 LAST HDL_TAP TRUE
J 0
(-2900 5025);
DISPLAY 0.872340 (-2900 5025);
DISPLAY INVISIBLE (-2900 5025);
FORCEPROP 1 LAST PATH I175
J 0
(-3227 5150);
DISPLAY 0.872340 (-3227 5150);
PAINT GREEN (-3227 5150);
DISPLAY INVISIBLE (-3227 5150);
FORCEADD TAP..1
(-3225 4950);
FORCEPROP 3 LASTPIN (-3275 4950) SIG_NAME M_K_CPU1_SA_DQ<17>
J 0
(-3265 4960);
DISPLAY 0.659574 (-3265 4960);
PAINT MONO (-3265 4960);
DISPLAY INVISIBLE (-3265 4960);
FORCEPROP 1 LASTPIN (-3275 4950) BN 17
J 0
(-3287 4958);
DISPLAY 0.489362 (-3287 4958);
PAINT GREEN (-3287 4958);
FORCEPROP 2 LAST CDS_LIB mstr_standard
J 0
(-3225 4950);
DISPLAY 0.723404 (-3225 4950);
PAINT MONO (-3225 4950);
DISPLAY INVISIBLE (-3225 4950);
FORCEPROP 1 LAST BODY_TYPE PLUMBING
J 0
(-3225 5000);
DISPLAY 0.872340 (-3225 5000);
PAINT GREEN (-3225 5000);
DISPLAY INVISIBLE (-3225 5000);
FORCEPROP 1 LAST HDL_TAP TRUE
J 0
(-2900 4825);
DISPLAY 0.872340 (-2900 4825);
DISPLAY INVISIBLE (-2900 4825);
FORCEPROP 1 LAST PATH I176
J 0
(-3227 4950);
DISPLAY 0.872340 (-3227 4950);
PAINT GREEN (-3227 4950);
DISPLAY INVISIBLE (-3227 4950);
FORCEADD TAP..1
(-3225 5100);
FORCEPROP 3 LASTPIN (-3275 5100) SIG_NAME M_K_CPU1_SA_DQ<15>
J 0
(-3265 5110);
DISPLAY 0.659574 (-3265 5110);
PAINT MONO (-3265 5110);
DISPLAY INVISIBLE (-3265 5110);
FORCEPROP 1 LASTPIN (-3275 5100) BN 15
J 0
(-3287 5108);
DISPLAY 0.489362 (-3287 5108);
PAINT GREEN (-3287 5108);
FORCEPROP 2 LAST CDS_LIB mstr_standard
J 0
(-3225 5100);
DISPLAY 0.723404 (-3225 5100);
PAINT MONO (-3225 5100);
DISPLAY INVISIBLE (-3225 5100);
FORCEPROP 1 LAST BODY_TYPE PLUMBING
J 0
(-3225 5150);
DISPLAY 0.872340 (-3225 5150);
PAINT GREEN (-3225 5150);
DISPLAY INVISIBLE (-3225 5150);
FORCEPROP 1 LAST HDL_TAP TRUE
J 0
(-2900 4975);
DISPLAY 0.872340 (-2900 4975);
DISPLAY INVISIBLE (-2900 4975);
FORCEPROP 1 LAST PATH I177
J 0
(-3227 5100);
DISPLAY 0.872340 (-3227 5100);
PAINT GREEN (-3227 5100);
DISPLAY INVISIBLE (-3227 5100);
FORCEADD TAP..1
(-3225 5000);
FORCEPROP 3 LASTPIN (-3275 5000) SIG_NAME M_K_CPU1_SA_DQ<16>
J 0
(-3265 5010);
DISPLAY 0.659574 (-3265 5010);
PAINT MONO (-3265 5010);
DISPLAY INVISIBLE (-3265 5010);
FORCEPROP 1 LASTPIN (-3275 5000) BN 16
J 0
(-3287 5008);
DISPLAY 0.489362 (-3287 5008);
PAINT GREEN (-3287 5008);
FORCEPROP 2 LAST CDS_LIB mstr_standard
J 0
(-3225 5000);
DISPLAY 0.723404 (-3225 5000);
PAINT MONO (-3225 5000);
DISPLAY INVISIBLE (-3225 5000);
FORCEPROP 1 LAST BODY_TYPE PLUMBING
J 0
(-3225 5050);
DISPLAY 0.872340 (-3225 5050);
PAINT GREEN (-3225 5050);
DISPLAY INVISIBLE (-3225 5050);
FORCEPROP 1 LAST HDL_TAP TRUE
J 0
(-2900 4875);
DISPLAY 0.872340 (-2900 4875);
DISPLAY INVISIBLE (-2900 4875);
FORCEPROP 1 LAST PATH I178
J 0
(-3227 5000);
DISPLAY 0.872340 (-3227 5000);
PAINT GREEN (-3227 5000);
DISPLAY INVISIBLE (-3227 5000);
FORCEADD TAP..1
(-3225 4900);
FORCEPROP 3 LASTPIN (-3275 4900) SIG_NAME M_K_CPU1_SA_DQ<18>
J 0
(-3265 4910);
DISPLAY 0.659574 (-3265 4910);
PAINT MONO (-3265 4910);
DISPLAY INVISIBLE (-3265 4910);
FORCEPROP 1 LASTPIN (-3275 4900) BN 18
J 0
(-3287 4908);
DISPLAY 0.489362 (-3287 4908);
PAINT GREEN (-3287 4908);
FORCEPROP 2 LAST CDS_LIB mstr_standard
J 0
(-3225 4900);
DISPLAY 0.723404 (-3225 4900);
PAINT MONO (-3225 4900);
DISPLAY INVISIBLE (-3225 4900);
FORCEPROP 1 LAST BODY_TYPE PLUMBING
J 0
(-3225 4950);
DISPLAY 0.872340 (-3225 4950);
PAINT GREEN (-3225 4950);
DISPLAY INVISIBLE (-3225 4950);
FORCEPROP 1 LAST HDL_TAP TRUE
J 0
(-2900 4775);
DISPLAY 0.872340 (-2900 4775);
DISPLAY INVISIBLE (-2900 4775);
FORCEPROP 1 LAST PATH I179
J 0
(-3227 4900);
DISPLAY 0.872340 (-3227 4900);
PAINT GREEN (-3227 4900);
DISPLAY INVISIBLE (-3227 4900);
FORCEADD TAP..1
(-3225 4850);
FORCEPROP 3 LASTPIN (-3275 4850) SIG_NAME M_K_CPU1_SA_DQ<19>
J 0
(-3265 4860);
DISPLAY 0.659574 (-3265 4860);
PAINT MONO (-3265 4860);
DISPLAY INVISIBLE (-3265 4860);
FORCEPROP 1 LASTPIN (-3275 4850) BN 19
J 0
(-3287 4858);
DISPLAY 0.489362 (-3287 4858);
PAINT GREEN (-3287 4858);
FORCEPROP 2 LAST CDS_LIB mstr_standard
J 0
(-3225 4850);
DISPLAY 0.723404 (-3225 4850);
PAINT MONO (-3225 4850);
DISPLAY INVISIBLE (-3225 4850);
FORCEPROP 1 LAST BODY_TYPE PLUMBING
J 0
(-3225 4900);
DISPLAY 0.872340 (-3225 4900);
PAINT GREEN (-3225 4900);
DISPLAY INVISIBLE (-3225 4900);
FORCEPROP 1 LAST HDL_TAP TRUE
J 0
(-2900 4725);
DISPLAY 0.872340 (-2900 4725);
DISPLAY INVISIBLE (-2900 4725);
FORCEPROP 1 LAST PATH I180
J 0
(-3227 4850);
DISPLAY 0.872340 (-3227 4850);
PAINT GREEN (-3227 4850);
DISPLAY INVISIBLE (-3227 4850);
FORCEADD TAP..1
(-3225 4800);
FORCEPROP 3 LASTPIN (-3275 4800) SIG_NAME M_K_CPU1_SA_DQ<20>
J 0
(-3265 4810);
DISPLAY 0.659574 (-3265 4810);
PAINT MONO (-3265 4810);
DISPLAY INVISIBLE (-3265 4810);
FORCEPROP 1 LASTPIN (-3275 4800) BN 20
J 0
(-3287 4808);
DISPLAY 0.489362 (-3287 4808);
PAINT GREEN (-3287 4808);
FORCEPROP 2 LAST CDS_LIB mstr_standard
J 0
(-3225 4800);
DISPLAY 0.723404 (-3225 4800);
PAINT MONO (-3225 4800);
DISPLAY INVISIBLE (-3225 4800);
FORCEPROP 1 LAST BODY_TYPE PLUMBING
J 0
(-3225 4850);
DISPLAY 0.872340 (-3225 4850);
PAINT GREEN (-3225 4850);
DISPLAY INVISIBLE (-3225 4850);
FORCEPROP 1 LAST HDL_TAP TRUE
J 0
(-2900 4675);
DISPLAY 0.872340 (-2900 4675);
DISPLAY INVISIBLE (-2900 4675);
FORCEPROP 1 LAST PATH I181
J 0
(-3227 4800);
DISPLAY 0.872340 (-3227 4800);
PAINT GREEN (-3227 4800);
DISPLAY INVISIBLE (-3227 4800);
FORCEADD TAP..1
(-3225 4750);
FORCEPROP 3 LASTPIN (-3275 4750) SIG_NAME M_K_CPU1_SA_DQ<21>
J 0
(-3265 4760);
DISPLAY 0.659574 (-3265 4760);
PAINT MONO (-3265 4760);
DISPLAY INVISIBLE (-3265 4760);
FORCEPROP 1 LASTPIN (-3275 4750) BN 21
J 0
(-3287 4758);
DISPLAY 0.489362 (-3287 4758);
PAINT GREEN (-3287 4758);
FORCEPROP 2 LAST CDS_LIB mstr_standard
J 0
(-3225 4750);
DISPLAY 0.723404 (-3225 4750);
PAINT MONO (-3225 4750);
DISPLAY INVISIBLE (-3225 4750);
FORCEPROP 1 LAST BODY_TYPE PLUMBING
J 0
(-3225 4800);
DISPLAY 0.872340 (-3225 4800);
PAINT GREEN (-3225 4800);
DISPLAY INVISIBLE (-3225 4800);
FORCEPROP 1 LAST HDL_TAP TRUE
J 0
(-2900 4625);
DISPLAY 0.872340 (-2900 4625);
DISPLAY INVISIBLE (-2900 4625);
FORCEPROP 1 LAST PATH I182
J 0
(-3227 4750);
DISPLAY 0.872340 (-3227 4750);
PAINT GREEN (-3227 4750);
DISPLAY INVISIBLE (-3227 4750);
FORCEADD TAP..1
(-3225 4700);
FORCEPROP 3 LASTPIN (-3275 4700) SIG_NAME M_K_CPU1_SA_DQ<22>
J 0
(-3265 4710);
DISPLAY 0.659574 (-3265 4710);
PAINT MONO (-3265 4710);
DISPLAY INVISIBLE (-3265 4710);
FORCEPROP 1 LASTPIN (-3275 4700) BN 22
J 0
(-3287 4708);
DISPLAY 0.489362 (-3287 4708);
PAINT GREEN (-3287 4708);
FORCEPROP 2 LAST CDS_LIB mstr_standard
J 0
(-3225 4700);
DISPLAY 0.723404 (-3225 4700);
PAINT MONO (-3225 4700);
DISPLAY INVISIBLE (-3225 4700);
FORCEPROP 1 LAST BODY_TYPE PLUMBING
J 0
(-3225 4750);
DISPLAY 0.872340 (-3225 4750);
PAINT GREEN (-3225 4750);
DISPLAY INVISIBLE (-3225 4750);
FORCEPROP 1 LAST HDL_TAP TRUE
J 0
(-2900 4575);
DISPLAY 0.872340 (-2900 4575);
DISPLAY INVISIBLE (-2900 4575);
FORCEPROP 1 LAST PATH I183
J 0
(-3227 4700);
DISPLAY 0.872340 (-3227 4700);
PAINT GREEN (-3227 4700);
DISPLAY INVISIBLE (-3227 4700);
FORCEADD TAP..1
(-3225 4650);
FORCEPROP 3 LASTPIN (-3275 4650) SIG_NAME M_K_CPU1_SA_DQ<23>
J 0
(-3265 4660);
DISPLAY 0.659574 (-3265 4660);
PAINT MONO (-3265 4660);
DISPLAY INVISIBLE (-3265 4660);
FORCEPROP 1 LASTPIN (-3275 4650) BN 23
J 0
(-3287 4658);
DISPLAY 0.489362 (-3287 4658);
PAINT GREEN (-3287 4658);
FORCEPROP 2 LAST CDS_LIB mstr_standard
J 0
(-3225 4650);
DISPLAY 0.723404 (-3225 4650);
PAINT MONO (-3225 4650);
DISPLAY INVISIBLE (-3225 4650);
FORCEPROP 1 LAST BODY_TYPE PLUMBING
J 0
(-3225 4700);
DISPLAY 0.872340 (-3225 4700);
PAINT GREEN (-3225 4700);
DISPLAY INVISIBLE (-3225 4700);
FORCEPROP 1 LAST HDL_TAP TRUE
J 0
(-2900 4525);
DISPLAY 0.872340 (-2900 4525);
DISPLAY INVISIBLE (-2900 4525);
FORCEPROP 1 LAST PATH I184
J 0
(-3227 4650);
DISPLAY 0.872340 (-3227 4650);
PAINT GREEN (-3227 4650);
DISPLAY INVISIBLE (-3227 4650);
FORCEADD TAP..1
(-3225 4550);
FORCEPROP 3 LASTPIN (-3275 4550) SIG_NAME M_K_CPU1_SA_DQ<24>
J 0
(-3265 4560);
DISPLAY 0.659574 (-3265 4560);
PAINT MONO (-3265 4560);
DISPLAY INVISIBLE (-3265 4560);
FORCEPROP 1 LASTPIN (-3275 4550) BN 24
J 0
(-3287 4558);
DISPLAY 0.489362 (-3287 4558);
PAINT GREEN (-3287 4558);
FORCEPROP 2 LAST CDS_LIB mstr_standard
J 0
(-3225 4550);
DISPLAY 0.723404 (-3225 4550);
PAINT MONO (-3225 4550);
DISPLAY INVISIBLE (-3225 4550);
FORCEPROP 1 LAST BODY_TYPE PLUMBING
J 0
(-3225 4600);
DISPLAY 0.872340 (-3225 4600);
PAINT GREEN (-3225 4600);
DISPLAY INVISIBLE (-3225 4600);
FORCEPROP 1 LAST HDL_TAP TRUE
J 0
(-2900 4425);
DISPLAY 0.872340 (-2900 4425);
DISPLAY INVISIBLE (-2900 4425);
FORCEPROP 1 LAST PATH I185
J 0
(-3227 4550);
DISPLAY 0.872340 (-3227 4550);
PAINT GREEN (-3227 4550);
DISPLAY INVISIBLE (-3227 4550);
FORCEADD TAP..1
(-3225 4500);
FORCEPROP 3 LASTPIN (-3275 4500) SIG_NAME M_K_CPU1_SA_DQ<25>
J 0
(-3265 4510);
DISPLAY 0.659574 (-3265 4510);
PAINT MONO (-3265 4510);
DISPLAY INVISIBLE (-3265 4510);
FORCEPROP 1 LASTPIN (-3275 4500) BN 25
J 0
(-3287 4508);
DISPLAY 0.489362 (-3287 4508);
PAINT GREEN (-3287 4508);
FORCEPROP 2 LAST CDS_LIB mstr_standard
J 0
(-3225 4500);
DISPLAY 0.723404 (-3225 4500);
PAINT MONO (-3225 4500);
DISPLAY INVISIBLE (-3225 4500);
FORCEPROP 1 LAST BODY_TYPE PLUMBING
J 0
(-3225 4550);
DISPLAY 0.872340 (-3225 4550);
PAINT GREEN (-3225 4550);
DISPLAY INVISIBLE (-3225 4550);
FORCEPROP 1 LAST HDL_TAP TRUE
J 0
(-2900 4375);
DISPLAY 0.872340 (-2900 4375);
DISPLAY INVISIBLE (-2900 4375);
FORCEPROP 1 LAST PATH I186
J 0
(-3227 4500);
DISPLAY 0.872340 (-3227 4500);
PAINT GREEN (-3227 4500);
DISPLAY INVISIBLE (-3227 4500);
FORCEADD TAP..1
(-3225 4450);
FORCEPROP 3 LASTPIN (-3275 4450) SIG_NAME M_K_CPU1_SA_DQ<26>
J 0
(-3265 4460);
DISPLAY 0.659574 (-3265 4460);
PAINT MONO (-3265 4460);
DISPLAY INVISIBLE (-3265 4460);
FORCEPROP 1 LASTPIN (-3275 4450) BN 26
J 0
(-3287 4458);
DISPLAY 0.489362 (-3287 4458);
PAINT GREEN (-3287 4458);
FORCEPROP 2 LAST CDS_LIB mstr_standard
J 0
(-3225 4450);
DISPLAY 0.723404 (-3225 4450);
PAINT MONO (-3225 4450);
DISPLAY INVISIBLE (-3225 4450);
FORCEPROP 1 LAST BODY_TYPE PLUMBING
J 0
(-3225 4500);
DISPLAY 0.872340 (-3225 4500);
PAINT GREEN (-3225 4500);
DISPLAY INVISIBLE (-3225 4500);
FORCEPROP 1 LAST HDL_TAP TRUE
J 0
(-2900 4325);
DISPLAY 0.872340 (-2900 4325);
DISPLAY INVISIBLE (-2900 4325);
FORCEPROP 1 LAST PATH I187
J 0
(-3227 4450);
DISPLAY 0.872340 (-3227 4450);
PAINT GREEN (-3227 4450);
DISPLAY INVISIBLE (-3227 4450);
FORCEADD TAP..1
(-3225 4400);
FORCEPROP 3 LASTPIN (-3275 4400) SIG_NAME M_K_CPU1_SA_DQ<27>
J 0
(-3265 4410);
DISPLAY 0.659574 (-3265 4410);
PAINT MONO (-3265 4410);
DISPLAY INVISIBLE (-3265 4410);
FORCEPROP 1 LASTPIN (-3275 4400) BN 27
J 0
(-3287 4408);
DISPLAY 0.489362 (-3287 4408);
PAINT GREEN (-3287 4408);
FORCEPROP 2 LAST CDS_LIB mstr_standard
J 0
(-3225 4400);
DISPLAY 0.723404 (-3225 4400);
PAINT MONO (-3225 4400);
DISPLAY INVISIBLE (-3225 4400);
FORCEPROP 1 LAST BODY_TYPE PLUMBING
J 0
(-3225 4450);
DISPLAY 0.872340 (-3225 4450);
PAINT GREEN (-3225 4450);
DISPLAY INVISIBLE (-3225 4450);
FORCEPROP 1 LAST HDL_TAP TRUE
J 0
(-2900 4275);
DISPLAY 0.872340 (-2900 4275);
DISPLAY INVISIBLE (-2900 4275);
FORCEPROP 1 LAST PATH I188
J 0
(-3227 4400);
DISPLAY 0.872340 (-3227 4400);
PAINT GREEN (-3227 4400);
DISPLAY INVISIBLE (-3227 4400);
FORCEADD TAP..1
(-3225 4350);
FORCEPROP 3 LASTPIN (-3275 4350) SIG_NAME M_K_CPU1_SA_DQ<28>
J 0
(-3265 4360);
DISPLAY 0.659574 (-3265 4360);
PAINT MONO (-3265 4360);
DISPLAY INVISIBLE (-3265 4360);
FORCEPROP 1 LASTPIN (-3275 4350) BN 28
J 0
(-3287 4358);
DISPLAY 0.489362 (-3287 4358);
PAINT GREEN (-3287 4358);
FORCEPROP 2 LAST CDS_LIB mstr_standard
J 0
(-3225 4350);
DISPLAY 0.723404 (-3225 4350);
PAINT MONO (-3225 4350);
DISPLAY INVISIBLE (-3225 4350);
FORCEPROP 1 LAST BODY_TYPE PLUMBING
J 0
(-3225 4400);
DISPLAY 0.872340 (-3225 4400);
PAINT GREEN (-3225 4400);
DISPLAY INVISIBLE (-3225 4400);
FORCEPROP 1 LAST HDL_TAP TRUE
J 0
(-2900 4225);
DISPLAY 0.872340 (-2900 4225);
DISPLAY INVISIBLE (-2900 4225);
FORCEPROP 1 LAST PATH I189
J 0
(-3227 4350);
DISPLAY 0.872340 (-3227 4350);
PAINT GREEN (-3227 4350);
DISPLAY INVISIBLE (-3227 4350);
FORCEADD TAP..1
(-3225 4300);
FORCEPROP 3 LASTPIN (-3275 4300) SIG_NAME M_K_CPU1_SA_DQ<29>
J 0
(-3265 4310);
DISPLAY 0.659574 (-3265 4310);
PAINT MONO (-3265 4310);
DISPLAY INVISIBLE (-3265 4310);
FORCEPROP 1 LASTPIN (-3275 4300) BN 29
J 0
(-3287 4308);
DISPLAY 0.489362 (-3287 4308);
PAINT GREEN (-3287 4308);
FORCEPROP 2 LAST CDS_LIB mstr_standard
J 0
(-3225 4300);
DISPLAY 0.723404 (-3225 4300);
PAINT MONO (-3225 4300);
DISPLAY INVISIBLE (-3225 4300);
FORCEPROP 1 LAST BODY_TYPE PLUMBING
J 0
(-3225 4350);
DISPLAY 0.872340 (-3225 4350);
PAINT GREEN (-3225 4350);
DISPLAY INVISIBLE (-3225 4350);
FORCEPROP 1 LAST HDL_TAP TRUE
J 0
(-2900 4175);
DISPLAY 0.872340 (-2900 4175);
DISPLAY INVISIBLE (-2900 4175);
FORCEPROP 1 LAST PATH I190
J 0
(-3227 4300);
DISPLAY 0.872340 (-3227 4300);
PAINT GREEN (-3227 4300);
DISPLAY INVISIBLE (-3227 4300);
FORCEADD TAP..1
(-3225 4250);
FORCEPROP 3 LASTPIN (-3275 4250) SIG_NAME M_K_CPU1_SA_DQ<30>
J 0
(-3265 4260);
DISPLAY 0.659574 (-3265 4260);
PAINT MONO (-3265 4260);
DISPLAY INVISIBLE (-3265 4260);
FORCEPROP 1 LASTPIN (-3275 4250) BN 30
J 0
(-3287 4258);
DISPLAY 0.489362 (-3287 4258);
PAINT GREEN (-3287 4258);
FORCEPROP 2 LAST CDS_LIB mstr_standard
J 0
(-3225 4250);
DISPLAY 0.723404 (-3225 4250);
PAINT MONO (-3225 4250);
DISPLAY INVISIBLE (-3225 4250);
FORCEPROP 1 LAST BODY_TYPE PLUMBING
J 0
(-3225 4300);
DISPLAY 0.872340 (-3225 4300);
PAINT GREEN (-3225 4300);
DISPLAY INVISIBLE (-3225 4300);
FORCEPROP 1 LAST HDL_TAP TRUE
J 0
(-2900 4125);
DISPLAY 0.872340 (-2900 4125);
DISPLAY INVISIBLE (-2900 4125);
FORCEPROP 1 LAST PATH I191
J 0
(-3227 4250);
DISPLAY 0.872340 (-3227 4250);
PAINT GREEN (-3227 4250);
DISPLAY INVISIBLE (-3227 4250);
FORCEADD TAP..1
(-3225 4200);
FORCEPROP 3 LASTPIN (-3275 4200) SIG_NAME M_K_CPU1_SA_DQ<31>
J 0
(-3265 4210);
DISPLAY 0.659574 (-3265 4210);
PAINT MONO (-3265 4210);
DISPLAY INVISIBLE (-3265 4210);
FORCEPROP 1 LASTPIN (-3275 4200) BN 31
J 0
(-3287 4208);
DISPLAY 0.489362 (-3287 4208);
PAINT GREEN (-3287 4208);
FORCEPROP 2 LAST CDS_LIB mstr_standard
J 0
(-3225 4200);
DISPLAY 0.723404 (-3225 4200);
PAINT MONO (-3225 4200);
DISPLAY INVISIBLE (-3225 4200);
FORCEPROP 1 LAST BODY_TYPE PLUMBING
J 0
(-3225 4250);
DISPLAY 0.872340 (-3225 4250);
PAINT GREEN (-3225 4250);
DISPLAY INVISIBLE (-3225 4250);
FORCEPROP 1 LAST HDL_TAP TRUE
J 0
(-2900 4075);
DISPLAY 0.872340 (-2900 4075);
DISPLAY INVISIBLE (-2900 4075);
FORCEPROP 1 LAST PATH I192
J 0
(-3227 4200);
DISPLAY 0.872340 (-3227 4200);
PAINT GREEN (-3227 4200);
DISPLAY INVISIBLE (-3227 4200);
FORCEADD TAP..1
(-3225 4100);
FORCEPROP 3 LASTPIN (-3275 4100) SIG_NAME M_K_CPU1_SB_DQ<0>
J 0
(-3265 4110);
DISPLAY 0.659574 (-3265 4110);
PAINT MONO (-3265 4110);
DISPLAY INVISIBLE (-3265 4110);
FORCEPROP 1 LASTPIN (-3275 4100) BN 0
J 0
(-3287 4108);
DISPLAY 0.489362 (-3287 4108);
PAINT GREEN (-3287 4108);
FORCEPROP 2 LAST CDS_LIB mstr_standard
J 0
(-3225 4100);
DISPLAY 0.723404 (-3225 4100);
PAINT MONO (-3225 4100);
DISPLAY INVISIBLE (-3225 4100);
FORCEPROP 1 LAST BODY_TYPE PLUMBING
J 0
(-3225 4150);
DISPLAY 0.872340 (-3225 4150);
PAINT GREEN (-3225 4150);
DISPLAY INVISIBLE (-3225 4150);
FORCEPROP 1 LAST HDL_TAP TRUE
J 0
(-2900 3975);
DISPLAY 0.872340 (-2900 3975);
DISPLAY INVISIBLE (-2900 3975);
FORCEPROP 1 LAST PATH I193
J 0
(-3227 4100);
DISPLAY 0.872340 (-3227 4100);
PAINT GREEN (-3227 4100);
DISPLAY INVISIBLE (-3227 4100);
FORCEADD OFFPAGE..3
(-2500 4125);
FORCEPROP 2 LAST $XR0 108 
J 0
(-2286 4125);
DISPLAY 0.638298 (-2286 4125);
PAINT MONO (-2286 4125);
FORCEPROP 2 LAST CDS_LIB mstr_standard
J 0
(-2500 4125);
DISPLAY 0.723404 (-2500 4125);
PAINT MONO (-2500 4125);
DISPLAY INVISIBLE (-2500 4125);
FORCEPROP 1 LAST OFFPAGE TRUE
J 0
(-2175 4000);
DISPLAY 0.872340 (-2175 4000);
PAINT GREEN (-2175 4000);
DISPLAY INVISIBLE (-2175 4000);
FORCEPROP 1 LAST COMMENT_BODY TRUE
J 0
(-2550 4025);
DISPLAY 0.872340 (-2550 4025);
PAINT GREEN (-2550 4025);
DISPLAY INVISIBLE (-2550 4025);
FORCEPROP 2 LAST PATH I194
J 0
(-2275 4175);
DISPLAY 1.021277 (-2275 4175);
DISPLAY INVISIBLE (-2275 4175);
FORCEADD OFFPAGE..6
R 2
(-2625 2350);
FORCEPROP 2 LAST $XR0 108 
J 0
(-2411 2350);
DISPLAY 0.638298 (-2411 2350);
PAINT MONO (-2411 2350);
FORCEPROP 2 LAST CDS_LIB mstr_standard
J 2
(-2625 2350);
DISPLAY 0.723404 (-2625 2350);
PAINT MONO (-2625 2350);
DISPLAY INVISIBLE (-2625 2350);
FORCEPROP 1 LAST OFFPAGE TRUE
J 2
(-2950 2225);
DISPLAY 0.872340 (-2950 2225);
PAINT GREEN (-2950 2225);
DISPLAY INVISIBLE (-2950 2225);
FORCEPROP 1 LAST COMMENT_BODY TRUE
J 2
(-2725 2275);
DISPLAY 0.872340 (-2725 2275);
PAINT GREEN (-2725 2275);
DISPLAY INVISIBLE (-2725 2275);
FORCEPROP 2 LAST PATH I195
J 0
(-2400 2400);
DISPLAY 1.021277 (-2400 2400);
DISPLAY INVISIBLE (-2400 2400);
FORCEADD TAP..1
(-3225 4050);
FORCEPROP 3 LASTPIN (-3275 4050) SIG_NAME M_K_CPU1_SB_DQ<1>
J 0
(-3265 4060);
DISPLAY 0.659574 (-3265 4060);
PAINT MONO (-3265 4060);
DISPLAY INVISIBLE (-3265 4060);
FORCEPROP 1 LASTPIN (-3275 4050) BN 1
J 0
(-3287 4058);
DISPLAY 0.489362 (-3287 4058);
PAINT GREEN (-3287 4058);
FORCEPROP 2 LAST CDS_LIB mstr_standard
J 0
(-3225 4050);
DISPLAY 0.723404 (-3225 4050);
PAINT MONO (-3225 4050);
DISPLAY INVISIBLE (-3225 4050);
FORCEPROP 1 LAST BODY_TYPE PLUMBING
J 0
(-3225 4100);
DISPLAY 0.872340 (-3225 4100);
PAINT GREEN (-3225 4100);
DISPLAY INVISIBLE (-3225 4100);
FORCEPROP 1 LAST HDL_TAP TRUE
J 0
(-2900 3925);
DISPLAY 0.872340 (-2900 3925);
DISPLAY INVISIBLE (-2900 3925);
FORCEPROP 1 LAST PATH I196
J 0
(-3227 4050);
DISPLAY 0.872340 (-3227 4050);
PAINT GREEN (-3227 4050);
DISPLAY INVISIBLE (-3227 4050);
FORCEADD TAP..1
(-3225 4000);
FORCEPROP 3 LASTPIN (-3275 4000) SIG_NAME M_K_CPU1_SB_DQ<2>
J 0
(-3265 4010);
DISPLAY 0.659574 (-3265 4010);
PAINT MONO (-3265 4010);
DISPLAY INVISIBLE (-3265 4010);
FORCEPROP 1 LASTPIN (-3275 4000) BN 2
J 0
(-3287 4008);
DISPLAY 0.489362 (-3287 4008);
PAINT GREEN (-3287 4008);
FORCEPROP 2 LAST CDS_LIB mstr_standard
J 0
(-3225 4000);
DISPLAY 0.723404 (-3225 4000);
PAINT MONO (-3225 4000);
DISPLAY INVISIBLE (-3225 4000);
FORCEPROP 1 LAST BODY_TYPE PLUMBING
J 0
(-3225 4050);
DISPLAY 0.872340 (-3225 4050);
PAINT GREEN (-3225 4050);
DISPLAY INVISIBLE (-3225 4050);
FORCEPROP 1 LAST HDL_TAP TRUE
J 0
(-2900 3875);
DISPLAY 0.872340 (-2900 3875);
DISPLAY INVISIBLE (-2900 3875);
FORCEPROP 1 LAST PATH I197
J 0
(-3227 4000);
DISPLAY 0.872340 (-3227 4000);
PAINT GREEN (-3227 4000);
DISPLAY INVISIBLE (-3227 4000);
FORCEADD TAP..1
(-3225 3950);
FORCEPROP 3 LASTPIN (-3275 3950) SIG_NAME M_K_CPU1_SB_DQ<3>
J 0
(-3265 3960);
DISPLAY 0.659574 (-3265 3960);
PAINT MONO (-3265 3960);
DISPLAY INVISIBLE (-3265 3960);
FORCEPROP 1 LASTPIN (-3275 3950) BN 3
J 0
(-3287 3958);
DISPLAY 0.489362 (-3287 3958);
PAINT GREEN (-3287 3958);
FORCEPROP 2 LAST CDS_LIB mstr_standard
J 0
(-3225 3950);
DISPLAY 0.723404 (-3225 3950);
PAINT MONO (-3225 3950);
DISPLAY INVISIBLE (-3225 3950);
FORCEPROP 1 LAST BODY_TYPE PLUMBING
J 0
(-3225 4000);
DISPLAY 0.872340 (-3225 4000);
PAINT GREEN (-3225 4000);
DISPLAY INVISIBLE (-3225 4000);
FORCEPROP 1 LAST HDL_TAP TRUE
J 0
(-2900 3825);
DISPLAY 0.872340 (-2900 3825);
DISPLAY INVISIBLE (-2900 3825);
FORCEPROP 1 LAST PATH I198
J 0
(-3227 3950);
DISPLAY 0.872340 (-3227 3950);
PAINT GREEN (-3227 3950);
DISPLAY INVISIBLE (-3227 3950);
FORCEADD TAP..1
(-3225 3850);
FORCEPROP 3 LASTPIN (-3275 3850) SIG_NAME M_K_CPU1_SB_DQ<5>
J 0
(-3265 3860);
DISPLAY 0.659574 (-3265 3860);
PAINT MONO (-3265 3860);
DISPLAY INVISIBLE (-3265 3860);
FORCEPROP 1 LASTPIN (-3275 3850) BN 5
J 0
(-3287 3858);
DISPLAY 0.489362 (-3287 3858);
PAINT GREEN (-3287 3858);
FORCEPROP 2 LAST CDS_LIB mstr_standard
J 0
(-3225 3850);
DISPLAY 0.723404 (-3225 3850);
PAINT MONO (-3225 3850);
DISPLAY INVISIBLE (-3225 3850);
FORCEPROP 1 LAST BODY_TYPE PLUMBING
J 0
(-3225 3900);
DISPLAY 0.872340 (-3225 3900);
PAINT GREEN (-3225 3900);
DISPLAY INVISIBLE (-3225 3900);
FORCEPROP 1 LAST HDL_TAP TRUE
J 0
(-2900 3725);
DISPLAY 0.872340 (-2900 3725);
DISPLAY INVISIBLE (-2900 3725);
FORCEPROP 1 LAST PATH I199
J 0
(-3227 3850);
DISPLAY 0.872340 (-3227 3850);
PAINT GREEN (-3227 3850);
DISPLAY INVISIBLE (-3227 3850);
FORCEADD TAP..1
(-3225 3900);
FORCEPROP 3 LASTPIN (-3275 3900) SIG_NAME M_K_CPU1_SB_DQ<4>
J 0
(-3265 3910);
DISPLAY 0.659574 (-3265 3910);
PAINT MONO (-3265 3910);
DISPLAY INVISIBLE (-3265 3910);
FORCEPROP 1 LASTPIN (-3275 3900) BN 4
J 0
(-3287 3908);
DISPLAY 0.489362 (-3287 3908);
PAINT GREEN (-3287 3908);
FORCEPROP 2 LAST CDS_LIB mstr_standard
J 0
(-3225 3900);
DISPLAY 0.723404 (-3225 3900);
PAINT MONO (-3225 3900);
DISPLAY INVISIBLE (-3225 3900);
FORCEPROP 1 LAST BODY_TYPE PLUMBING
J 0
(-3225 3950);
DISPLAY 0.872340 (-3225 3950);
PAINT GREEN (-3225 3950);
DISPLAY INVISIBLE (-3225 3950);
FORCEPROP 1 LAST HDL_TAP TRUE
J 0
(-2900 3775);
DISPLAY 0.872340 (-2900 3775);
DISPLAY INVISIBLE (-2900 3775);
FORCEPROP 1 LAST PATH I200
J 0
(-3227 3900);
DISPLAY 0.872340 (-3227 3900);
PAINT GREEN (-3227 3900);
DISPLAY INVISIBLE (-3227 3900);
FORCEADD TAP..1
(-3225 3800);
FORCEPROP 3 LASTPIN (-3275 3800) SIG_NAME M_K_CPU1_SB_DQ<6>
J 0
(-3265 3810);
DISPLAY 0.659574 (-3265 3810);
PAINT MONO (-3265 3810);
DISPLAY INVISIBLE (-3265 3810);
FORCEPROP 1 LASTPIN (-3275 3800) BN 6
J 0
(-3287 3808);
DISPLAY 0.489362 (-3287 3808);
PAINT GREEN (-3287 3808);
FORCEPROP 2 LAST CDS_LIB mstr_standard
J 0
(-3225 3800);
DISPLAY 0.723404 (-3225 3800);
PAINT MONO (-3225 3800);
DISPLAY INVISIBLE (-3225 3800);
FORCEPROP 1 LAST BODY_TYPE PLUMBING
J 0
(-3225 3850);
DISPLAY 0.872340 (-3225 3850);
PAINT GREEN (-3225 3850);
DISPLAY INVISIBLE (-3225 3850);
FORCEPROP 1 LAST HDL_TAP TRUE
J 0
(-2900 3675);
DISPLAY 0.872340 (-2900 3675);
DISPLAY INVISIBLE (-2900 3675);
FORCEPROP 1 LAST PATH I201
J 0
(-3227 3800);
DISPLAY 0.872340 (-3227 3800);
PAINT GREEN (-3227 3800);
DISPLAY INVISIBLE (-3227 3800);
FORCEADD TAP..1
(-3225 3750);
FORCEPROP 3 LASTPIN (-3275 3750) SIG_NAME M_K_CPU1_SB_DQ<7>
J 0
(-3265 3760);
DISPLAY 0.659574 (-3265 3760);
PAINT MONO (-3265 3760);
DISPLAY INVISIBLE (-3265 3760);
FORCEPROP 1 LASTPIN (-3275 3750) BN 7
J 0
(-3287 3758);
DISPLAY 0.489362 (-3287 3758);
PAINT GREEN (-3287 3758);
FORCEPROP 2 LAST CDS_LIB mstr_standard
J 0
(-3225 3750);
DISPLAY 0.723404 (-3225 3750);
PAINT MONO (-3225 3750);
DISPLAY INVISIBLE (-3225 3750);
FORCEPROP 1 LAST BODY_TYPE PLUMBING
J 0
(-3225 3800);
DISPLAY 0.872340 (-3225 3800);
PAINT GREEN (-3225 3800);
DISPLAY INVISIBLE (-3225 3800);
FORCEPROP 1 LAST HDL_TAP TRUE
J 0
(-2900 3625);
DISPLAY 0.872340 (-2900 3625);
DISPLAY INVISIBLE (-2900 3625);
FORCEPROP 1 LAST PATH I202
J 0
(-3227 3750);
DISPLAY 0.872340 (-3227 3750);
PAINT GREEN (-3227 3750);
DISPLAY INVISIBLE (-3227 3750);
FORCEADD TAP..1
(-3225 3600);
FORCEPROP 3 LASTPIN (-3275 3600) SIG_NAME M_K_CPU1_SB_DQ<9>
J 0
(-3265 3610);
DISPLAY 0.659574 (-3265 3610);
PAINT MONO (-3265 3610);
DISPLAY INVISIBLE (-3265 3610);
FORCEPROP 1 LASTPIN (-3275 3600) BN 9
J 0
(-3287 3608);
DISPLAY 0.489362 (-3287 3608);
PAINT GREEN (-3287 3608);
FORCEPROP 2 LAST CDS_LIB mstr_standard
J 0
(-3225 3600);
DISPLAY 0.723404 (-3225 3600);
PAINT MONO (-3225 3600);
DISPLAY INVISIBLE (-3225 3600);
FORCEPROP 1 LAST BODY_TYPE PLUMBING
J 0
(-3225 3650);
DISPLAY 0.872340 (-3225 3650);
PAINT GREEN (-3225 3650);
DISPLAY INVISIBLE (-3225 3650);
FORCEPROP 1 LAST HDL_TAP TRUE
J 0
(-2900 3475);
DISPLAY 0.872340 (-2900 3475);
DISPLAY INVISIBLE (-2900 3475);
FORCEPROP 1 LAST PATH I203
J 0
(-3227 3600);
DISPLAY 0.872340 (-3227 3600);
PAINT GREEN (-3227 3600);
DISPLAY INVISIBLE (-3227 3600);
FORCEADD TAP..1
(-3225 3650);
FORCEPROP 3 LASTPIN (-3275 3650) SIG_NAME M_K_CPU1_SB_DQ<8>
J 0
(-3265 3660);
DISPLAY 0.659574 (-3265 3660);
PAINT MONO (-3265 3660);
DISPLAY INVISIBLE (-3265 3660);
FORCEPROP 1 LASTPIN (-3275 3650) BN 8
J 0
(-3287 3658);
DISPLAY 0.489362 (-3287 3658);
PAINT GREEN (-3287 3658);
FORCEPROP 2 LAST CDS_LIB mstr_standard
J 0
(-3225 3650);
DISPLAY 0.723404 (-3225 3650);
PAINT MONO (-3225 3650);
DISPLAY INVISIBLE (-3225 3650);
FORCEPROP 1 LAST BODY_TYPE PLUMBING
J 0
(-3225 3700);
DISPLAY 0.872340 (-3225 3700);
PAINT GREEN (-3225 3700);
DISPLAY INVISIBLE (-3225 3700);
FORCEPROP 1 LAST HDL_TAP TRUE
J 0
(-2900 3525);
DISPLAY 0.872340 (-2900 3525);
DISPLAY INVISIBLE (-2900 3525);
FORCEPROP 1 LAST PATH I204
J 0
(-3227 3650);
DISPLAY 0.872340 (-3227 3650);
PAINT GREEN (-3227 3650);
DISPLAY INVISIBLE (-3227 3650);
FORCEADD TAP..1
(-3225 3550);
FORCEPROP 3 LASTPIN (-3275 3550) SIG_NAME M_K_CPU1_SB_DQ<10>
J 0
(-3265 3560);
DISPLAY 0.659574 (-3265 3560);
PAINT MONO (-3265 3560);
DISPLAY INVISIBLE (-3265 3560);
FORCEPROP 1 LASTPIN (-3275 3550) BN 10
J 0
(-3287 3558);
DISPLAY 0.489362 (-3287 3558);
PAINT GREEN (-3287 3558);
FORCEPROP 2 LAST CDS_LIB mstr_standard
J 0
(-3225 3550);
DISPLAY 0.723404 (-3225 3550);
PAINT MONO (-3225 3550);
DISPLAY INVISIBLE (-3225 3550);
FORCEPROP 1 LAST BODY_TYPE PLUMBING
J 0
(-3225 3600);
DISPLAY 0.872340 (-3225 3600);
PAINT GREEN (-3225 3600);
DISPLAY INVISIBLE (-3225 3600);
FORCEPROP 1 LAST HDL_TAP TRUE
J 0
(-2900 3425);
DISPLAY 0.872340 (-2900 3425);
DISPLAY INVISIBLE (-2900 3425);
FORCEPROP 1 LAST PATH I205
J 0
(-3227 3550);
DISPLAY 0.872340 (-3227 3550);
PAINT GREEN (-3227 3550);
DISPLAY INVISIBLE (-3227 3550);
FORCEADD TAP..1
(-3225 3500);
FORCEPROP 3 LASTPIN (-3275 3500) SIG_NAME M_K_CPU1_SB_DQ<11>
J 0
(-3265 3510);
DISPLAY 0.659574 (-3265 3510);
PAINT MONO (-3265 3510);
DISPLAY INVISIBLE (-3265 3510);
FORCEPROP 1 LASTPIN (-3275 3500) BN 11
J 0
(-3287 3508);
DISPLAY 0.489362 (-3287 3508);
PAINT GREEN (-3287 3508);
FORCEPROP 2 LAST CDS_LIB mstr_standard
J 0
(-3225 3500);
DISPLAY 0.723404 (-3225 3500);
PAINT MONO (-3225 3500);
DISPLAY INVISIBLE (-3225 3500);
FORCEPROP 1 LAST BODY_TYPE PLUMBING
J 0
(-3225 3550);
DISPLAY 0.872340 (-3225 3550);
PAINT GREEN (-3225 3550);
DISPLAY INVISIBLE (-3225 3550);
FORCEPROP 1 LAST HDL_TAP TRUE
J 0
(-2900 3375);
DISPLAY 0.872340 (-2900 3375);
DISPLAY INVISIBLE (-2900 3375);
FORCEPROP 1 LAST PATH I206
J 0
(-3227 3500);
DISPLAY 0.872340 (-3227 3500);
PAINT GREEN (-3227 3500);
DISPLAY INVISIBLE (-3227 3500);
FORCEADD TAP..1
(-3225 3450);
FORCEPROP 3 LASTPIN (-3275 3450) SIG_NAME M_K_CPU1_SB_DQ<12>
J 0
(-3265 3460);
DISPLAY 0.659574 (-3265 3460);
PAINT MONO (-3265 3460);
DISPLAY INVISIBLE (-3265 3460);
FORCEPROP 1 LASTPIN (-3275 3450) BN 12
J 0
(-3287 3458);
DISPLAY 0.489362 (-3287 3458);
PAINT GREEN (-3287 3458);
FORCEPROP 2 LAST CDS_LIB mstr_standard
J 0
(-3225 3450);
DISPLAY 0.723404 (-3225 3450);
PAINT MONO (-3225 3450);
DISPLAY INVISIBLE (-3225 3450);
FORCEPROP 1 LAST BODY_TYPE PLUMBING
J 0
(-3225 3500);
DISPLAY 0.872340 (-3225 3500);
PAINT GREEN (-3225 3500);
DISPLAY INVISIBLE (-3225 3500);
FORCEPROP 1 LAST HDL_TAP TRUE
J 0
(-2900 3325);
DISPLAY 0.872340 (-2900 3325);
DISPLAY INVISIBLE (-2900 3325);
FORCEPROP 1 LAST PATH I207
J 0
(-3227 3450);
DISPLAY 0.872340 (-3227 3450);
PAINT GREEN (-3227 3450);
DISPLAY INVISIBLE (-3227 3450);
FORCEADD TAP..1
(-3225 3350);
FORCEPROP 3 LASTPIN (-3275 3350) SIG_NAME M_K_CPU1_SB_DQ<14>
J 0
(-3265 3360);
DISPLAY 0.659574 (-3265 3360);
PAINT MONO (-3265 3360);
DISPLAY INVISIBLE (-3265 3360);
FORCEPROP 1 LASTPIN (-3275 3350) BN 14
J 0
(-3287 3358);
DISPLAY 0.489362 (-3287 3358);
PAINT GREEN (-3287 3358);
FORCEPROP 2 LAST CDS_LIB mstr_standard
J 0
(-3225 3350);
DISPLAY 0.723404 (-3225 3350);
PAINT MONO (-3225 3350);
DISPLAY INVISIBLE (-3225 3350);
FORCEPROP 1 LAST BODY_TYPE PLUMBING
J 0
(-3225 3400);
DISPLAY 0.872340 (-3225 3400);
PAINT GREEN (-3225 3400);
DISPLAY INVISIBLE (-3225 3400);
FORCEPROP 1 LAST HDL_TAP TRUE
J 0
(-2900 3225);
DISPLAY 0.872340 (-2900 3225);
DISPLAY INVISIBLE (-2900 3225);
FORCEPROP 1 LAST PATH I208
J 0
(-3227 3350);
DISPLAY 0.872340 (-3227 3350);
PAINT GREEN (-3227 3350);
DISPLAY INVISIBLE (-3227 3350);
FORCEADD TAP..1
(-3225 3400);
FORCEPROP 3 LASTPIN (-3275 3400) SIG_NAME M_K_CPU1_SB_DQ<13>
J 0
(-3265 3410);
DISPLAY 0.659574 (-3265 3410);
PAINT MONO (-3265 3410);
DISPLAY INVISIBLE (-3265 3410);
FORCEPROP 1 LASTPIN (-3275 3400) BN 13
J 0
(-3287 3408);
DISPLAY 0.489362 (-3287 3408);
PAINT GREEN (-3287 3408);
FORCEPROP 2 LAST CDS_LIB mstr_standard
J 0
(-3225 3400);
DISPLAY 0.723404 (-3225 3400);
PAINT MONO (-3225 3400);
DISPLAY INVISIBLE (-3225 3400);
FORCEPROP 1 LAST BODY_TYPE PLUMBING
J 0
(-3225 3450);
DISPLAY 0.872340 (-3225 3450);
PAINT GREEN (-3225 3450);
DISPLAY INVISIBLE (-3225 3450);
FORCEPROP 1 LAST HDL_TAP TRUE
J 0
(-2900 3275);
DISPLAY 0.872340 (-2900 3275);
DISPLAY INVISIBLE (-2900 3275);
FORCEPROP 1 LAST PATH I209
J 0
(-3227 3400);
DISPLAY 0.872340 (-3227 3400);
PAINT GREEN (-3227 3400);
DISPLAY INVISIBLE (-3227 3400);
FORCEADD TAP..1
(-3225 3300);
FORCEPROP 3 LASTPIN (-3275 3300) SIG_NAME M_K_CPU1_SB_DQ<15>
J 0
(-3265 3310);
DISPLAY 0.659574 (-3265 3310);
PAINT MONO (-3265 3310);
DISPLAY INVISIBLE (-3265 3310);
FORCEPROP 1 LASTPIN (-3275 3300) BN 15
J 0
(-3287 3308);
DISPLAY 0.489362 (-3287 3308);
PAINT GREEN (-3287 3308);
FORCEPROP 2 LAST CDS_LIB mstr_standard
J 0
(-3225 3300);
DISPLAY 0.723404 (-3225 3300);
PAINT MONO (-3225 3300);
DISPLAY INVISIBLE (-3225 3300);
FORCEPROP 1 LAST BODY_TYPE PLUMBING
J 0
(-3225 3350);
DISPLAY 0.872340 (-3225 3350);
PAINT GREEN (-3225 3350);
DISPLAY INVISIBLE (-3225 3350);
FORCEPROP 1 LAST HDL_TAP TRUE
J 0
(-2900 3175);
DISPLAY 0.872340 (-2900 3175);
DISPLAY INVISIBLE (-2900 3175);
FORCEPROP 1 LAST PATH I210
J 0
(-3227 3300);
DISPLAY 0.872340 (-3227 3300);
PAINT GREEN (-3227 3300);
DISPLAY INVISIBLE (-3227 3300);
FORCEADD TAP..1
(-3225 3200);
FORCEPROP 3 LASTPIN (-3275 3200) SIG_NAME M_K_CPU1_SB_DQ<16>
J 0
(-3265 3210);
DISPLAY 0.659574 (-3265 3210);
PAINT MONO (-3265 3210);
DISPLAY INVISIBLE (-3265 3210);
FORCEPROP 1 LASTPIN (-3275 3200) BN 16
J 0
(-3287 3208);
DISPLAY 0.489362 (-3287 3208);
PAINT GREEN (-3287 3208);
FORCEPROP 2 LAST CDS_LIB mstr_standard
J 0
(-3225 3200);
DISPLAY 0.723404 (-3225 3200);
PAINT MONO (-3225 3200);
DISPLAY INVISIBLE (-3225 3200);
FORCEPROP 1 LAST BODY_TYPE PLUMBING
J 0
(-3225 3250);
DISPLAY 0.872340 (-3225 3250);
PAINT GREEN (-3225 3250);
DISPLAY INVISIBLE (-3225 3250);
FORCEPROP 1 LAST HDL_TAP TRUE
J 0
(-2900 3075);
DISPLAY 0.872340 (-2900 3075);
DISPLAY INVISIBLE (-2900 3075);
FORCEPROP 1 LAST PATH I211
J 0
(-3227 3200);
DISPLAY 0.872340 (-3227 3200);
PAINT GREEN (-3227 3200);
DISPLAY INVISIBLE (-3227 3200);
FORCEADD TAP..1
(-3225 3150);
FORCEPROP 3 LASTPIN (-3275 3150) SIG_NAME M_K_CPU1_SB_DQ<17>
J 0
(-3265 3160);
DISPLAY 0.659574 (-3265 3160);
PAINT MONO (-3265 3160);
DISPLAY INVISIBLE (-3265 3160);
FORCEPROP 1 LASTPIN (-3275 3150) BN 17
J 0
(-3287 3158);
DISPLAY 0.489362 (-3287 3158);
PAINT GREEN (-3287 3158);
FORCEPROP 2 LAST CDS_LIB mstr_standard
J 0
(-3225 3150);
DISPLAY 0.723404 (-3225 3150);
PAINT MONO (-3225 3150);
DISPLAY INVISIBLE (-3225 3150);
FORCEPROP 1 LAST BODY_TYPE PLUMBING
J 0
(-3225 3200);
DISPLAY 0.872340 (-3225 3200);
PAINT GREEN (-3225 3200);
DISPLAY INVISIBLE (-3225 3200);
FORCEPROP 1 LAST HDL_TAP TRUE
J 0
(-2900 3025);
DISPLAY 0.872340 (-2900 3025);
DISPLAY INVISIBLE (-2900 3025);
FORCEPROP 1 LAST PATH I212
J 0
(-3227 3150);
DISPLAY 0.872340 (-3227 3150);
PAINT GREEN (-3227 3150);
DISPLAY INVISIBLE (-3227 3150);
FORCEADD TAP..1
(-3225 3100);
FORCEPROP 3 LASTPIN (-3275 3100) SIG_NAME M_K_CPU1_SB_DQ<18>
J 0
(-3265 3110);
DISPLAY 0.659574 (-3265 3110);
PAINT MONO (-3265 3110);
DISPLAY INVISIBLE (-3265 3110);
FORCEPROP 1 LASTPIN (-3275 3100) BN 18
J 0
(-3287 3108);
DISPLAY 0.489362 (-3287 3108);
PAINT GREEN (-3287 3108);
FORCEPROP 2 LAST CDS_LIB mstr_standard
J 0
(-3225 3100);
DISPLAY 0.723404 (-3225 3100);
PAINT MONO (-3225 3100);
DISPLAY INVISIBLE (-3225 3100);
FORCEPROP 1 LAST BODY_TYPE PLUMBING
J 0
(-3225 3150);
DISPLAY 0.872340 (-3225 3150);
PAINT GREEN (-3225 3150);
DISPLAY INVISIBLE (-3225 3150);
FORCEPROP 1 LAST HDL_TAP TRUE
J 0
(-2900 2975);
DISPLAY 0.872340 (-2900 2975);
DISPLAY INVISIBLE (-2900 2975);
FORCEPROP 1 LAST PATH I213
J 0
(-3227 3100);
DISPLAY 0.872340 (-3227 3100);
PAINT GREEN (-3227 3100);
DISPLAY INVISIBLE (-3227 3100);
FORCEADD TAP..1
(-3225 3050);
FORCEPROP 3 LASTPIN (-3275 3050) SIG_NAME M_K_CPU1_SB_DQ<19>
J 0
(-3265 3060);
DISPLAY 0.659574 (-3265 3060);
PAINT MONO (-3265 3060);
DISPLAY INVISIBLE (-3265 3060);
FORCEPROP 1 LASTPIN (-3275 3050) BN 19
J 0
(-3287 3058);
DISPLAY 0.489362 (-3287 3058);
PAINT GREEN (-3287 3058);
FORCEPROP 2 LAST CDS_LIB mstr_standard
J 0
(-3225 3050);
DISPLAY 0.723404 (-3225 3050);
PAINT MONO (-3225 3050);
DISPLAY INVISIBLE (-3225 3050);
FORCEPROP 1 LAST BODY_TYPE PLUMBING
J 0
(-3225 3100);
DISPLAY 0.872340 (-3225 3100);
PAINT GREEN (-3225 3100);
DISPLAY INVISIBLE (-3225 3100);
FORCEPROP 1 LAST HDL_TAP TRUE
J 0
(-2900 2925);
DISPLAY 0.872340 (-2900 2925);
DISPLAY INVISIBLE (-2900 2925);
FORCEPROP 1 LAST PATH I214
J 0
(-3227 3050);
DISPLAY 0.872340 (-3227 3050);
PAINT GREEN (-3227 3050);
DISPLAY INVISIBLE (-3227 3050);
FORCEADD TAP..1
(-3225 2950);
FORCEPROP 3 LASTPIN (-3275 2950) SIG_NAME M_K_CPU1_SB_DQ<21>
J 0
(-3265 2960);
DISPLAY 0.659574 (-3265 2960);
PAINT MONO (-3265 2960);
DISPLAY INVISIBLE (-3265 2960);
FORCEPROP 1 LASTPIN (-3275 2950) BN 21
J 0
(-3287 2958);
DISPLAY 0.489362 (-3287 2958);
PAINT GREEN (-3287 2958);
FORCEPROP 2 LAST CDS_LIB mstr_standard
J 0
(-3225 2950);
DISPLAY 0.723404 (-3225 2950);
PAINT MONO (-3225 2950);
DISPLAY INVISIBLE (-3225 2950);
FORCEPROP 1 LAST BODY_TYPE PLUMBING
J 0
(-3225 3000);
DISPLAY 0.872340 (-3225 3000);
PAINT GREEN (-3225 3000);
DISPLAY INVISIBLE (-3225 3000);
FORCEPROP 1 LAST HDL_TAP TRUE
J 0
(-2900 2825);
DISPLAY 0.872340 (-2900 2825);
DISPLAY INVISIBLE (-2900 2825);
FORCEPROP 1 LAST PATH I215
J 0
(-3227 2950);
DISPLAY 0.872340 (-3227 2950);
PAINT GREEN (-3227 2950);
DISPLAY INVISIBLE (-3227 2950);
FORCEADD TAP..1
(-3225 3000);
FORCEPROP 3 LASTPIN (-3275 3000) SIG_NAME M_K_CPU1_SB_DQ<20>
J 0
(-3265 3010);
DISPLAY 0.659574 (-3265 3010);
PAINT MONO (-3265 3010);
DISPLAY INVISIBLE (-3265 3010);
FORCEPROP 1 LASTPIN (-3275 3000) BN 20
J 0
(-3287 3008);
DISPLAY 0.489362 (-3287 3008);
PAINT GREEN (-3287 3008);
FORCEPROP 2 LAST CDS_LIB mstr_standard
J 0
(-3225 3000);
DISPLAY 0.723404 (-3225 3000);
PAINT MONO (-3225 3000);
DISPLAY INVISIBLE (-3225 3000);
FORCEPROP 1 LAST BODY_TYPE PLUMBING
J 0
(-3225 3050);
DISPLAY 0.872340 (-3225 3050);
PAINT GREEN (-3225 3050);
DISPLAY INVISIBLE (-3225 3050);
FORCEPROP 1 LAST HDL_TAP TRUE
J 0
(-2900 2875);
DISPLAY 0.872340 (-2900 2875);
DISPLAY INVISIBLE (-2900 2875);
FORCEPROP 1 LAST PATH I216
J 0
(-3227 3000);
DISPLAY 0.872340 (-3227 3000);
PAINT GREEN (-3227 3000);
DISPLAY INVISIBLE (-3227 3000);
FORCEADD TAP..1
(-3225 2900);
FORCEPROP 3 LASTPIN (-3275 2900) SIG_NAME M_K_CPU1_SB_DQ<22>
J 0
(-3265 2910);
DISPLAY 0.659574 (-3265 2910);
PAINT MONO (-3265 2910);
DISPLAY INVISIBLE (-3265 2910);
FORCEPROP 1 LASTPIN (-3275 2900) BN 22
J 0
(-3287 2908);
DISPLAY 0.489362 (-3287 2908);
PAINT GREEN (-3287 2908);
FORCEPROP 2 LAST CDS_LIB mstr_standard
J 0
(-3225 2900);
DISPLAY 0.723404 (-3225 2900);
PAINT MONO (-3225 2900);
DISPLAY INVISIBLE (-3225 2900);
FORCEPROP 1 LAST BODY_TYPE PLUMBING
J 0
(-3225 2950);
DISPLAY 0.872340 (-3225 2950);
PAINT GREEN (-3225 2950);
DISPLAY INVISIBLE (-3225 2950);
FORCEPROP 1 LAST HDL_TAP TRUE
J 0
(-2900 2775);
DISPLAY 0.872340 (-2900 2775);
DISPLAY INVISIBLE (-2900 2775);
FORCEPROP 1 LAST PATH I217
J 0
(-3227 2900);
DISPLAY 0.872340 (-3227 2900);
PAINT GREEN (-3227 2900);
DISPLAY INVISIBLE (-3227 2900);
FORCEADD TAP..1
(-3225 2850);
FORCEPROP 3 LASTPIN (-3275 2850) SIG_NAME M_K_CPU1_SB_DQ<23>
J 0
(-3265 2860);
DISPLAY 0.659574 (-3265 2860);
PAINT MONO (-3265 2860);
DISPLAY INVISIBLE (-3265 2860);
FORCEPROP 1 LASTPIN (-3275 2850) BN 23
J 0
(-3287 2858);
DISPLAY 0.489362 (-3287 2858);
PAINT GREEN (-3287 2858);
FORCEPROP 2 LAST CDS_LIB mstr_standard
J 0
(-3225 2850);
DISPLAY 0.723404 (-3225 2850);
PAINT MONO (-3225 2850);
DISPLAY INVISIBLE (-3225 2850);
FORCEPROP 1 LAST BODY_TYPE PLUMBING
J 0
(-3225 2900);
DISPLAY 0.872340 (-3225 2900);
PAINT GREEN (-3225 2900);
DISPLAY INVISIBLE (-3225 2900);
FORCEPROP 1 LAST HDL_TAP TRUE
J 0
(-2900 2725);
DISPLAY 0.872340 (-2900 2725);
DISPLAY INVISIBLE (-2900 2725);
FORCEPROP 1 LAST PATH I218
J 0
(-3227 2850);
DISPLAY 0.872340 (-3227 2850);
PAINT GREEN (-3227 2850);
DISPLAY INVISIBLE (-3227 2850);
FORCEADD TAP..1
(-3225 2750);
FORCEPROP 3 LASTPIN (-3275 2750) SIG_NAME M_K_CPU1_SB_DQ<24>
J 0
(-3265 2760);
DISPLAY 0.659574 (-3265 2760);
PAINT MONO (-3265 2760);
DISPLAY INVISIBLE (-3265 2760);
FORCEPROP 1 LASTPIN (-3275 2750) BN 24
J 0
(-3287 2758);
DISPLAY 0.489362 (-3287 2758);
PAINT GREEN (-3287 2758);
FORCEPROP 2 LAST CDS_LIB mstr_standard
J 0
(-3225 2750);
DISPLAY 0.723404 (-3225 2750);
PAINT MONO (-3225 2750);
DISPLAY INVISIBLE (-3225 2750);
FORCEPROP 1 LAST BODY_TYPE PLUMBING
J 0
(-3225 2800);
DISPLAY 0.872340 (-3225 2800);
PAINT GREEN (-3225 2800);
DISPLAY INVISIBLE (-3225 2800);
FORCEPROP 1 LAST HDL_TAP TRUE
J 0
(-2900 2625);
DISPLAY 0.872340 (-2900 2625);
DISPLAY INVISIBLE (-2900 2625);
FORCEPROP 1 LAST PATH I219
J 0
(-3227 2750);
DISPLAY 0.872340 (-3227 2750);
PAINT GREEN (-3227 2750);
DISPLAY INVISIBLE (-3227 2750);
FORCEADD TAP..1
(-3225 2700);
FORCEPROP 3 LASTPIN (-3275 2700) SIG_NAME M_K_CPU1_SB_DQ<25>
J 0
(-3265 2710);
DISPLAY 0.659574 (-3265 2710);
PAINT MONO (-3265 2710);
DISPLAY INVISIBLE (-3265 2710);
FORCEPROP 1 LASTPIN (-3275 2700) BN 25
J 0
(-3287 2708);
DISPLAY 0.489362 (-3287 2708);
PAINT GREEN (-3287 2708);
FORCEPROP 2 LAST CDS_LIB mstr_standard
J 0
(-3225 2700);
DISPLAY 0.723404 (-3225 2700);
PAINT MONO (-3225 2700);
DISPLAY INVISIBLE (-3225 2700);
FORCEPROP 1 LAST BODY_TYPE PLUMBING
J 0
(-3225 2750);
DISPLAY 0.872340 (-3225 2750);
PAINT GREEN (-3225 2750);
DISPLAY INVISIBLE (-3225 2750);
FORCEPROP 1 LAST HDL_TAP TRUE
J 0
(-2900 2575);
DISPLAY 0.872340 (-2900 2575);
DISPLAY INVISIBLE (-2900 2575);
FORCEPROP 1 LAST PATH I220
J 0
(-3227 2700);
DISPLAY 0.872340 (-3227 2700);
PAINT GREEN (-3227 2700);
DISPLAY INVISIBLE (-3227 2700);
FORCEADD TAP..1
(-3225 2650);
FORCEPROP 3 LASTPIN (-3275 2650) SIG_NAME M_K_CPU1_SB_DQ<26>
J 0
(-3265 2660);
DISPLAY 0.659574 (-3265 2660);
PAINT MONO (-3265 2660);
DISPLAY INVISIBLE (-3265 2660);
FORCEPROP 1 LASTPIN (-3275 2650) BN 26
J 0
(-3287 2658);
DISPLAY 0.489362 (-3287 2658);
PAINT GREEN (-3287 2658);
FORCEPROP 2 LAST CDS_LIB mstr_standard
J 0
(-3225 2650);
DISPLAY 0.723404 (-3225 2650);
PAINT MONO (-3225 2650);
DISPLAY INVISIBLE (-3225 2650);
FORCEPROP 1 LAST BODY_TYPE PLUMBING
J 0
(-3225 2700);
DISPLAY 0.872340 (-3225 2700);
PAINT GREEN (-3225 2700);
DISPLAY INVISIBLE (-3225 2700);
FORCEPROP 1 LAST HDL_TAP TRUE
J 0
(-2900 2525);
DISPLAY 0.872340 (-2900 2525);
DISPLAY INVISIBLE (-2900 2525);
FORCEPROP 1 LAST PATH I221
J 0
(-3227 2650);
DISPLAY 0.872340 (-3227 2650);
PAINT GREEN (-3227 2650);
DISPLAY INVISIBLE (-3227 2650);
FORCEADD TAP..1
(-3225 2600);
FORCEPROP 3 LASTPIN (-3275 2600) SIG_NAME M_K_CPU1_SB_DQ<27>
J 0
(-3265 2610);
DISPLAY 0.659574 (-3265 2610);
PAINT MONO (-3265 2610);
DISPLAY INVISIBLE (-3265 2610);
FORCEPROP 1 LASTPIN (-3275 2600) BN 27
J 0
(-3287 2608);
DISPLAY 0.489362 (-3287 2608);
PAINT GREEN (-3287 2608);
FORCEPROP 2 LAST CDS_LIB mstr_standard
J 0
(-3225 2600);
DISPLAY 0.723404 (-3225 2600);
PAINT MONO (-3225 2600);
DISPLAY INVISIBLE (-3225 2600);
FORCEPROP 1 LAST BODY_TYPE PLUMBING
J 0
(-3225 2650);
DISPLAY 0.872340 (-3225 2650);
PAINT GREEN (-3225 2650);
DISPLAY INVISIBLE (-3225 2650);
FORCEPROP 1 LAST HDL_TAP TRUE
J 0
(-2900 2475);
DISPLAY 0.872340 (-2900 2475);
DISPLAY INVISIBLE (-2900 2475);
FORCEPROP 1 LAST PATH I222
J 0
(-3227 2600);
DISPLAY 0.872340 (-3227 2600);
PAINT GREEN (-3227 2600);
DISPLAY INVISIBLE (-3227 2600);
FORCEADD TAP..1
(-3225 2500);
FORCEPROP 3 LASTPIN (-3275 2500) SIG_NAME M_K_CPU1_SB_DQ<29>
J 0
(-3265 2510);
DISPLAY 0.659574 (-3265 2510);
PAINT MONO (-3265 2510);
DISPLAY INVISIBLE (-3265 2510);
FORCEPROP 1 LASTPIN (-3275 2500) BN 29
J 0
(-3287 2508);
DISPLAY 0.489362 (-3287 2508);
PAINT GREEN (-3287 2508);
FORCEPROP 2 LAST CDS_LIB mstr_standard
J 0
(-3225 2500);
DISPLAY 0.723404 (-3225 2500);
PAINT MONO (-3225 2500);
DISPLAY INVISIBLE (-3225 2500);
FORCEPROP 1 LAST BODY_TYPE PLUMBING
J 0
(-3225 2550);
DISPLAY 0.872340 (-3225 2550);
PAINT GREEN (-3225 2550);
DISPLAY INVISIBLE (-3225 2550);
FORCEPROP 1 LAST HDL_TAP TRUE
J 0
(-2900 2375);
DISPLAY 0.872340 (-2900 2375);
DISPLAY INVISIBLE (-2900 2375);
FORCEPROP 1 LAST PATH I223
J 0
(-3227 2500);
DISPLAY 0.872340 (-3227 2500);
PAINT GREEN (-3227 2500);
DISPLAY INVISIBLE (-3227 2500);
FORCEADD TAP..1
(-3225 2550);
FORCEPROP 3 LASTPIN (-3275 2550) SIG_NAME M_K_CPU1_SB_DQ<28>
J 0
(-3265 2560);
DISPLAY 0.659574 (-3265 2560);
PAINT MONO (-3265 2560);
DISPLAY INVISIBLE (-3265 2560);
FORCEPROP 1 LASTPIN (-3275 2550) BN 28
J 0
(-3287 2558);
DISPLAY 0.489362 (-3287 2558);
PAINT GREEN (-3287 2558);
FORCEPROP 2 LAST CDS_LIB mstr_standard
J 0
(-3225 2550);
DISPLAY 0.723404 (-3225 2550);
PAINT MONO (-3225 2550);
DISPLAY INVISIBLE (-3225 2550);
FORCEPROP 1 LAST BODY_TYPE PLUMBING
J 0
(-3225 2600);
DISPLAY 0.872340 (-3225 2600);
PAINT GREEN (-3225 2600);
DISPLAY INVISIBLE (-3225 2600);
FORCEPROP 1 LAST HDL_TAP TRUE
J 0
(-2900 2425);
DISPLAY 0.872340 (-2900 2425);
DISPLAY INVISIBLE (-2900 2425);
FORCEPROP 1 LAST PATH I224
J 0
(-3227 2550);
DISPLAY 0.872340 (-3227 2550);
PAINT GREEN (-3227 2550);
DISPLAY INVISIBLE (-3227 2550);
FORCEADD TAP..1
(-3225 2450);
FORCEPROP 3 LASTPIN (-3275 2450) SIG_NAME M_K_CPU1_SB_DQ<30>
J 0
(-3265 2460);
DISPLAY 0.659574 (-3265 2460);
PAINT MONO (-3265 2460);
DISPLAY INVISIBLE (-3265 2460);
FORCEPROP 1 LASTPIN (-3275 2450) BN 30
J 0
(-3287 2458);
DISPLAY 0.489362 (-3287 2458);
PAINT GREEN (-3287 2458);
FORCEPROP 2 LAST CDS_LIB mstr_standard
J 0
(-3225 2450);
DISPLAY 0.723404 (-3225 2450);
PAINT MONO (-3225 2450);
DISPLAY INVISIBLE (-3225 2450);
FORCEPROP 1 LAST BODY_TYPE PLUMBING
J 0
(-3225 2500);
DISPLAY 0.872340 (-3225 2500);
PAINT GREEN (-3225 2500);
DISPLAY INVISIBLE (-3225 2500);
FORCEPROP 1 LAST HDL_TAP TRUE
J 0
(-2900 2325);
DISPLAY 0.872340 (-2900 2325);
DISPLAY INVISIBLE (-2900 2325);
FORCEPROP 1 LAST PATH I225
J 0
(-3227 2450);
DISPLAY 0.872340 (-3227 2450);
PAINT GREEN (-3227 2450);
DISPLAY INVISIBLE (-3227 2450);
FORCEADD TAP..1
(-3225 2400);
FORCEPROP 3 LASTPIN (-3275 2400) SIG_NAME M_K_CPU1_SB_DQ<31>
J 0
(-3265 2410);
DISPLAY 0.659574 (-3265 2410);
PAINT MONO (-3265 2410);
DISPLAY INVISIBLE (-3265 2410);
FORCEPROP 1 LASTPIN (-3275 2400) BN 31
J 0
(-3287 2408);
DISPLAY 0.489362 (-3287 2408);
PAINT GREEN (-3287 2408);
FORCEPROP 2 LAST CDS_LIB mstr_standard
J 0
(-3225 2400);
DISPLAY 0.723404 (-3225 2400);
PAINT MONO (-3225 2400);
DISPLAY INVISIBLE (-3225 2400);
FORCEPROP 1 LAST BODY_TYPE PLUMBING
J 0
(-3225 2450);
DISPLAY 0.872340 (-3225 2450);
PAINT GREEN (-3225 2450);
DISPLAY INVISIBLE (-3225 2450);
FORCEPROP 1 LAST HDL_TAP TRUE
J 0
(-2900 2275);
DISPLAY 0.872340 (-2900 2275);
DISPLAY INVISIBLE (-2900 2275);
FORCEPROP 1 LAST PATH I226
J 0
(-3227 2400);
DISPLAY 0.872340 (-3227 2400);
PAINT GREEN (-3227 2400);
DISPLAY INVISIBLE (-3227 2400);
FORCEADD TAP..1
(-3225 2300);
FORCEPROP 3 LASTPIN (-3275 2300) SIG_NAME M_K_CPU1_SA_CB<0>
J 0
(-3265 2310);
DISPLAY 0.659574 (-3265 2310);
PAINT MONO (-3265 2310);
DISPLAY INVISIBLE (-3265 2310);
FORCEPROP 1 LASTPIN (-3275 2300) BN 0
J 0
(-3287 2308);
DISPLAY 0.489362 (-3287 2308);
PAINT GREEN (-3287 2308);
FORCEPROP 2 LAST CDS_LIB mstr_standard
J 2
(-3225 2300);
DISPLAY 0.723404 (-3225 2300);
PAINT MONO (-3225 2300);
DISPLAY INVISIBLE (-3225 2300);
FORCEPROP 1 LAST BODY_TYPE PLUMBING
J 0
(-3225 2350);
DISPLAY 0.872340 (-3225 2350);
PAINT GREEN (-3225 2350);
DISPLAY INVISIBLE (-3225 2350);
FORCEPROP 1 LAST HDL_TAP TRUE
J 0
(-2900 2175);
DISPLAY 0.872340 (-2900 2175);
DISPLAY INVISIBLE (-2900 2175);
FORCEPROP 1 LAST PATH I227
J 0
(-3227 2300);
DISPLAY 0.872340 (-3227 2300);
PAINT GREEN (-3227 2300);
DISPLAY INVISIBLE (-3227 2300);
FORCEADD TAP..1
(-3225 2250);
FORCEPROP 3 LASTPIN (-3275 2250) SIG_NAME M_K_CPU1_SA_CB<1>
J 0
(-3265 2260);
DISPLAY 0.659574 (-3265 2260);
PAINT MONO (-3265 2260);
DISPLAY INVISIBLE (-3265 2260);
FORCEPROP 1 LASTPIN (-3275 2250) BN 1
J 0
(-3287 2258);
DISPLAY 0.489362 (-3287 2258);
PAINT GREEN (-3287 2258);
FORCEPROP 2 LAST CDS_LIB mstr_standard
J 2
(-3225 2250);
DISPLAY 0.723404 (-3225 2250);
PAINT MONO (-3225 2250);
DISPLAY INVISIBLE (-3225 2250);
FORCEPROP 1 LAST BODY_TYPE PLUMBING
J 0
(-3225 2300);
DISPLAY 0.872340 (-3225 2300);
PAINT GREEN (-3225 2300);
DISPLAY INVISIBLE (-3225 2300);
FORCEPROP 1 LAST HDL_TAP TRUE
J 0
(-2900 2125);
DISPLAY 0.872340 (-2900 2125);
DISPLAY INVISIBLE (-2900 2125);
FORCEPROP 1 LAST PATH I228
J 0
(-3227 2250);
DISPLAY 0.872340 (-3227 2250);
PAINT GREEN (-3227 2250);
DISPLAY INVISIBLE (-3227 2250);
FORCEADD TAP..1
(-3225 2200);
FORCEPROP 3 LASTPIN (-3275 2200) SIG_NAME M_K_CPU1_SA_CB<2>
J 0
(-3265 2210);
DISPLAY 0.659574 (-3265 2210);
PAINT MONO (-3265 2210);
DISPLAY INVISIBLE (-3265 2210);
FORCEPROP 1 LASTPIN (-3275 2200) BN 2
J 0
(-3287 2208);
DISPLAY 0.489362 (-3287 2208);
PAINT GREEN (-3287 2208);
FORCEPROP 2 LAST CDS_LIB mstr_standard
J 2
(-3225 2200);
DISPLAY 0.723404 (-3225 2200);
PAINT MONO (-3225 2200);
DISPLAY INVISIBLE (-3225 2200);
FORCEPROP 1 LAST BODY_TYPE PLUMBING
J 0
(-3225 2250);
DISPLAY 0.872340 (-3225 2250);
PAINT GREEN (-3225 2250);
DISPLAY INVISIBLE (-3225 2250);
FORCEPROP 1 LAST HDL_TAP TRUE
J 0
(-2900 2075);
DISPLAY 0.872340 (-2900 2075);
DISPLAY INVISIBLE (-2900 2075);
FORCEPROP 1 LAST PATH I229
J 0
(-3227 2200);
DISPLAY 0.872340 (-3227 2200);
PAINT GREEN (-3227 2200);
DISPLAY INVISIBLE (-3227 2200);
FORCEADD TAP..1
(-3225 2150);
FORCEPROP 3 LASTPIN (-3275 2150) SIG_NAME M_K_CPU1_SA_CB<3>
J 0
(-3265 2160);
DISPLAY 0.659574 (-3265 2160);
PAINT MONO (-3265 2160);
DISPLAY INVISIBLE (-3265 2160);
FORCEPROP 1 LASTPIN (-3275 2150) BN 3
J 0
(-3287 2158);
DISPLAY 0.489362 (-3287 2158);
PAINT GREEN (-3287 2158);
FORCEPROP 2 LAST CDS_LIB mstr_standard
J 2
(-3225 2150);
DISPLAY 0.723404 (-3225 2150);
PAINT MONO (-3225 2150);
DISPLAY INVISIBLE (-3225 2150);
FORCEPROP 1 LAST BODY_TYPE PLUMBING
J 0
(-3225 2200);
DISPLAY 0.872340 (-3225 2200);
PAINT GREEN (-3225 2200);
DISPLAY INVISIBLE (-3225 2200);
FORCEPROP 1 LAST HDL_TAP TRUE
J 0
(-2900 2025);
DISPLAY 0.872340 (-2900 2025);
DISPLAY INVISIBLE (-2900 2025);
FORCEPROP 1 LAST PATH I230
J 0
(-3227 2150);
DISPLAY 0.872340 (-3227 2150);
PAINT GREEN (-3227 2150);
DISPLAY INVISIBLE (-3227 2150);
FORCEADD TAP..1
(-3225 2100);
FORCEPROP 3 LASTPIN (-3275 2100) SIG_NAME M_K_CPU1_SA_CB<4>
J 0
(-3265 2110);
DISPLAY 0.659574 (-3265 2110);
PAINT MONO (-3265 2110);
DISPLAY INVISIBLE (-3265 2110);
FORCEPROP 1 LASTPIN (-3275 2100) BN 4
J 0
(-3287 2108);
DISPLAY 0.489362 (-3287 2108);
PAINT GREEN (-3287 2108);
FORCEPROP 2 LAST CDS_LIB mstr_standard
J 2
(-3225 2100);
DISPLAY 0.723404 (-3225 2100);
PAINT MONO (-3225 2100);
DISPLAY INVISIBLE (-3225 2100);
FORCEPROP 1 LAST BODY_TYPE PLUMBING
J 0
(-3225 2150);
DISPLAY 0.872340 (-3225 2150);
PAINT GREEN (-3225 2150);
DISPLAY INVISIBLE (-3225 2150);
FORCEPROP 1 LAST HDL_TAP TRUE
J 0
(-2900 1975);
DISPLAY 0.872340 (-2900 1975);
DISPLAY INVISIBLE (-2900 1975);
FORCEPROP 1 LAST PATH I231
J 0
(-3227 2100);
DISPLAY 0.872340 (-3227 2100);
PAINT GREEN (-3227 2100);
DISPLAY INVISIBLE (-3227 2100);
FORCEADD TAP..1
(-3225 2050);
FORCEPROP 3 LASTPIN (-3275 2050) SIG_NAME M_K_CPU1_SA_CB<5>
J 0
(-3265 2060);
DISPLAY 0.659574 (-3265 2060);
PAINT MONO (-3265 2060);
DISPLAY INVISIBLE (-3265 2060);
FORCEPROP 1 LASTPIN (-3275 2050) BN 5
J 0
(-3287 2058);
DISPLAY 0.489362 (-3287 2058);
PAINT GREEN (-3287 2058);
FORCEPROP 2 LAST CDS_LIB mstr_standard
J 2
(-3225 2050);
DISPLAY 0.723404 (-3225 2050);
PAINT MONO (-3225 2050);
DISPLAY INVISIBLE (-3225 2050);
FORCEPROP 1 LAST BODY_TYPE PLUMBING
J 0
(-3225 2100);
DISPLAY 0.872340 (-3225 2100);
PAINT GREEN (-3225 2100);
DISPLAY INVISIBLE (-3225 2100);
FORCEPROP 1 LAST HDL_TAP TRUE
J 0
(-2900 1925);
DISPLAY 0.872340 (-2900 1925);
DISPLAY INVISIBLE (-2900 1925);
FORCEPROP 1 LAST PATH I232
J 0
(-3227 2050);
DISPLAY 0.872340 (-3227 2050);
PAINT GREEN (-3227 2050);
DISPLAY INVISIBLE (-3227 2050);
FORCEADD OFFPAGE..6
R 2
(-2625 1900);
FORCEPROP 2 LAST $XR0 108 
J 0
(-2411 1900);
DISPLAY 0.638298 (-2411 1900);
PAINT MONO (-2411 1900);
FORCEPROP 2 LAST CDS_LIB mstr_standard
J 2
(-2625 1900);
DISPLAY 0.723404 (-2625 1900);
PAINT MONO (-2625 1900);
DISPLAY INVISIBLE (-2625 1900);
FORCEPROP 1 LAST OFFPAGE TRUE
J 2
(-2950 1775);
DISPLAY 0.872340 (-2950 1775);
PAINT GREEN (-2950 1775);
DISPLAY INVISIBLE (-2950 1775);
FORCEPROP 1 LAST COMMENT_BODY TRUE
J 2
(-2725 1825);
DISPLAY 0.872340 (-2725 1825);
PAINT GREEN (-2725 1825);
DISPLAY INVISIBLE (-2725 1825);
FORCEPROP 2 LAST PATH I233
J 0
(-2400 1950);
DISPLAY 1.021277 (-2400 1950);
DISPLAY INVISIBLE (-2400 1950);
FORCEADD TAP..1
(-3225 2000);
FORCEPROP 3 LASTPIN (-3275 2000) SIG_NAME M_K_CPU1_SA_CB<6>
J 0
(-3265 2010);
DISPLAY 0.659574 (-3265 2010);
PAINT MONO (-3265 2010);
DISPLAY INVISIBLE (-3265 2010);
FORCEPROP 1 LASTPIN (-3275 2000) BN 6
J 0
(-3287 2008);
DISPLAY 0.489362 (-3287 2008);
PAINT GREEN (-3287 2008);
FORCEPROP 2 LAST CDS_LIB mstr_standard
J 2
(-3225 2000);
DISPLAY 0.723404 (-3225 2000);
PAINT MONO (-3225 2000);
DISPLAY INVISIBLE (-3225 2000);
FORCEPROP 1 LAST BODY_TYPE PLUMBING
J 0
(-3225 2050);
DISPLAY 0.872340 (-3225 2050);
PAINT GREEN (-3225 2050);
DISPLAY INVISIBLE (-3225 2050);
FORCEPROP 1 LAST HDL_TAP TRUE
J 0
(-2900 1875);
DISPLAY 0.872340 (-2900 1875);
DISPLAY INVISIBLE (-2900 1875);
FORCEPROP 1 LAST PATH I234
J 0
(-3227 2000);
DISPLAY 0.872340 (-3227 2000);
PAINT GREEN (-3227 2000);
DISPLAY INVISIBLE (-3227 2000);
FORCEADD TAP..1
(-3225 1950);
FORCEPROP 3 LASTPIN (-3275 1950) SIG_NAME M_K_CPU1_SA_CB<7>
J 0
(-3265 1960);
DISPLAY 0.659574 (-3265 1960);
PAINT MONO (-3265 1960);
DISPLAY INVISIBLE (-3265 1960);
FORCEPROP 1 LASTPIN (-3275 1950) BN 7
J 0
(-3287 1958);
DISPLAY 0.489362 (-3287 1958);
PAINT GREEN (-3287 1958);
FORCEPROP 2 LAST CDS_LIB mstr_standard
J 2
(-3225 1950);
DISPLAY 0.723404 (-3225 1950);
PAINT MONO (-3225 1950);
DISPLAY INVISIBLE (-3225 1950);
FORCEPROP 1 LAST BODY_TYPE PLUMBING
J 0
(-3225 2000);
DISPLAY 0.872340 (-3225 2000);
PAINT GREEN (-3225 2000);
DISPLAY INVISIBLE (-3225 2000);
FORCEPROP 1 LAST HDL_TAP TRUE
J 0
(-2900 1825);
DISPLAY 0.872340 (-2900 1825);
DISPLAY INVISIBLE (-2900 1825);
FORCEPROP 1 LAST PATH I235
J 0
(-3227 1950);
DISPLAY 0.872340 (-3227 1950);
PAINT GREEN (-3227 1950);
DISPLAY INVISIBLE (-3227 1950);
FORCEADD TAP..1
(-3225 1800);
FORCEPROP 3 LASTPIN (-3275 1800) SIG_NAME M_K_CPU1_SB_CB<1>
J 0
(-3265 1810);
DISPLAY 0.659574 (-3265 1810);
PAINT MONO (-3265 1810);
DISPLAY INVISIBLE (-3265 1810);
FORCEPROP 1 LASTPIN (-3275 1800) BN 1
J 0
(-3287 1808);
DISPLAY 0.489362 (-3287 1808);
PAINT GREEN (-3287 1808);
FORCEPROP 2 LAST CDS_LIB mstr_standard
J 2
(-3225 1800);
DISPLAY 0.723404 (-3225 1800);
PAINT MONO (-3225 1800);
DISPLAY INVISIBLE (-3225 1800);
FORCEPROP 1 LAST BODY_TYPE PLUMBING
J 0
(-3225 1850);
DISPLAY 0.872340 (-3225 1850);
PAINT GREEN (-3225 1850);
DISPLAY INVISIBLE (-3225 1850);
FORCEPROP 1 LAST HDL_TAP TRUE
J 0
(-2900 1675);
DISPLAY 0.872340 (-2900 1675);
DISPLAY INVISIBLE (-2900 1675);
FORCEPROP 1 LAST PATH I236
J 0
(-3227 1800);
DISPLAY 0.872340 (-3227 1800);
PAINT GREEN (-3227 1800);
DISPLAY INVISIBLE (-3227 1800);
FORCEADD TAP..1
(-3225 1850);
FORCEPROP 3 LASTPIN (-3275 1850) SIG_NAME M_K_CPU1_SB_CB<0>
J 0
(-3265 1860);
DISPLAY 0.659574 (-3265 1860);
PAINT MONO (-3265 1860);
DISPLAY INVISIBLE (-3265 1860);
FORCEPROP 1 LASTPIN (-3275 1850) BN 0
J 0
(-3287 1858);
DISPLAY 0.489362 (-3287 1858);
PAINT GREEN (-3287 1858);
FORCEPROP 2 LAST CDS_LIB mstr_standard
J 2
(-3225 1850);
DISPLAY 0.723404 (-3225 1850);
PAINT MONO (-3225 1850);
DISPLAY INVISIBLE (-3225 1850);
FORCEPROP 1 LAST BODY_TYPE PLUMBING
J 0
(-3225 1900);
DISPLAY 0.872340 (-3225 1900);
PAINT GREEN (-3225 1900);
DISPLAY INVISIBLE (-3225 1900);
FORCEPROP 1 LAST HDL_TAP TRUE
J 0
(-2900 1725);
DISPLAY 0.872340 (-2900 1725);
DISPLAY INVISIBLE (-2900 1725);
FORCEPROP 1 LAST PATH I237
J 0
(-3227 1850);
DISPLAY 0.872340 (-3227 1850);
PAINT GREEN (-3227 1850);
DISPLAY INVISIBLE (-3227 1850);
FORCEADD TAP..1
(-3225 1750);
FORCEPROP 3 LASTPIN (-3275 1750) SIG_NAME M_K_CPU1_SB_CB<2>
J 0
(-3265 1760);
DISPLAY 0.659574 (-3265 1760);
PAINT MONO (-3265 1760);
DISPLAY INVISIBLE (-3265 1760);
FORCEPROP 1 LASTPIN (-3275 1750) BN 2
J 0
(-3287 1758);
DISPLAY 0.489362 (-3287 1758);
PAINT GREEN (-3287 1758);
FORCEPROP 2 LAST CDS_LIB mstr_standard
J 2
(-3225 1750);
DISPLAY 0.723404 (-3225 1750);
PAINT MONO (-3225 1750);
DISPLAY INVISIBLE (-3225 1750);
FORCEPROP 1 LAST BODY_TYPE PLUMBING
J 0
(-3225 1800);
DISPLAY 0.872340 (-3225 1800);
PAINT GREEN (-3225 1800);
DISPLAY INVISIBLE (-3225 1800);
FORCEPROP 1 LAST HDL_TAP TRUE
J 0
(-2900 1625);
DISPLAY 0.872340 (-2900 1625);
DISPLAY INVISIBLE (-2900 1625);
FORCEPROP 1 LAST PATH I238
J 0
(-3227 1750);
DISPLAY 0.872340 (-3227 1750);
PAINT GREEN (-3227 1750);
DISPLAY INVISIBLE (-3227 1750);
FORCEADD TAP..1
(-3225 1700);
FORCEPROP 3 LASTPIN (-3275 1700) SIG_NAME M_K_CPU1_SB_CB<3>
J 0
(-3265 1710);
DISPLAY 0.659574 (-3265 1710);
PAINT MONO (-3265 1710);
DISPLAY INVISIBLE (-3265 1710);
FORCEPROP 1 LASTPIN (-3275 1700) BN 3
J 0
(-3287 1708);
DISPLAY 0.489362 (-3287 1708);
PAINT GREEN (-3287 1708);
FORCEPROP 2 LAST CDS_LIB mstr_standard
J 2
(-3225 1700);
DISPLAY 0.723404 (-3225 1700);
PAINT MONO (-3225 1700);
DISPLAY INVISIBLE (-3225 1700);
FORCEPROP 1 LAST BODY_TYPE PLUMBING
J 0
(-3225 1750);
DISPLAY 0.872340 (-3225 1750);
PAINT GREEN (-3225 1750);
DISPLAY INVISIBLE (-3225 1750);
FORCEPROP 1 LAST HDL_TAP TRUE
J 0
(-2900 1575);
DISPLAY 0.872340 (-2900 1575);
DISPLAY INVISIBLE (-2900 1575);
FORCEPROP 1 LAST PATH I239
J 0
(-3227 1700);
DISPLAY 0.872340 (-3227 1700);
PAINT GREEN (-3227 1700);
DISPLAY INVISIBLE (-3227 1700);
FORCEADD TAP..1
(-3225 1600);
FORCEPROP 3 LASTPIN (-3275 1600) SIG_NAME M_K_CPU1_SB_CB<5>
J 0
(-3265 1610);
DISPLAY 0.659574 (-3265 1610);
PAINT MONO (-3265 1610);
DISPLAY INVISIBLE (-3265 1610);
FORCEPROP 1 LASTPIN (-3275 1600) BN 5
J 0
(-3287 1608);
DISPLAY 0.489362 (-3287 1608);
PAINT GREEN (-3287 1608);
FORCEPROP 2 LAST CDS_LIB mstr_standard
J 2
(-3225 1600);
DISPLAY 0.723404 (-3225 1600);
PAINT MONO (-3225 1600);
DISPLAY INVISIBLE (-3225 1600);
FORCEPROP 1 LAST BODY_TYPE PLUMBING
J 0
(-3225 1650);
DISPLAY 0.872340 (-3225 1650);
PAINT GREEN (-3225 1650);
DISPLAY INVISIBLE (-3225 1650);
FORCEPROP 1 LAST HDL_TAP TRUE
J 0
(-2900 1475);
DISPLAY 0.872340 (-2900 1475);
DISPLAY INVISIBLE (-2900 1475);
FORCEPROP 1 LAST PATH I240
J 0
(-3227 1600);
DISPLAY 0.872340 (-3227 1600);
PAINT GREEN (-3227 1600);
DISPLAY INVISIBLE (-3227 1600);
FORCEADD TAP..1
(-3225 1650);
FORCEPROP 3 LASTPIN (-3275 1650) SIG_NAME M_K_CPU1_SB_CB<4>
J 0
(-3265 1660);
DISPLAY 0.659574 (-3265 1660);
PAINT MONO (-3265 1660);
DISPLAY INVISIBLE (-3265 1660);
FORCEPROP 1 LASTPIN (-3275 1650) BN 4
J 0
(-3287 1658);
DISPLAY 0.489362 (-3287 1658);
PAINT GREEN (-3287 1658);
FORCEPROP 2 LAST CDS_LIB mstr_standard
J 2
(-3225 1650);
DISPLAY 0.723404 (-3225 1650);
PAINT MONO (-3225 1650);
DISPLAY INVISIBLE (-3225 1650);
FORCEPROP 1 LAST BODY_TYPE PLUMBING
J 0
(-3225 1700);
DISPLAY 0.872340 (-3225 1700);
PAINT GREEN (-3225 1700);
DISPLAY INVISIBLE (-3225 1700);
FORCEPROP 1 LAST HDL_TAP TRUE
J 0
(-2900 1525);
DISPLAY 0.872340 (-2900 1525);
DISPLAY INVISIBLE (-2900 1525);
FORCEPROP 1 LAST PATH I241
J 0
(-3227 1650);
DISPLAY 0.872340 (-3227 1650);
PAINT GREEN (-3227 1650);
DISPLAY INVISIBLE (-3227 1650);
FORCEADD TAP..1
(-3225 1550);
FORCEPROP 3 LASTPIN (-3275 1550) SIG_NAME M_K_CPU1_SB_CB<6>
J 0
(-3265 1560);
DISPLAY 0.659574 (-3265 1560);
PAINT MONO (-3265 1560);
DISPLAY INVISIBLE (-3265 1560);
FORCEPROP 1 LASTPIN (-3275 1550) BN 6
J 0
(-3287 1558);
DISPLAY 0.489362 (-3287 1558);
PAINT GREEN (-3287 1558);
FORCEPROP 2 LAST CDS_LIB mstr_standard
J 2
(-3225 1550);
DISPLAY 0.723404 (-3225 1550);
PAINT MONO (-3225 1550);
DISPLAY INVISIBLE (-3225 1550);
FORCEPROP 1 LAST BODY_TYPE PLUMBING
J 0
(-3225 1600);
DISPLAY 0.872340 (-3225 1600);
PAINT GREEN (-3225 1600);
DISPLAY INVISIBLE (-3225 1600);
FORCEPROP 1 LAST HDL_TAP TRUE
J 0
(-2900 1425);
DISPLAY 0.872340 (-2900 1425);
DISPLAY INVISIBLE (-2900 1425);
FORCEPROP 1 LAST PATH I242
J 0
(-3227 1550);
DISPLAY 0.872340 (-3227 1550);
PAINT GREEN (-3227 1550);
DISPLAY INVISIBLE (-3227 1550);
FORCEADD TAP..1
(-3225 1500);
FORCEPROP 3 LASTPIN (-3275 1500) SIG_NAME M_K_CPU1_SB_CB<7>
J 0
(-3265 1510);
DISPLAY 0.659574 (-3265 1510);
PAINT MONO (-3265 1510);
DISPLAY INVISIBLE (-3265 1510);
FORCEPROP 1 LASTPIN (-3275 1500) BN 7
J 0
(-3287 1508);
DISPLAY 0.489362 (-3287 1508);
PAINT GREEN (-3287 1508);
FORCEPROP 2 LAST CDS_LIB mstr_standard
J 2
(-3225 1500);
DISPLAY 0.723404 (-3225 1500);
PAINT MONO (-3225 1500);
DISPLAY INVISIBLE (-3225 1500);
FORCEPROP 1 LAST BODY_TYPE PLUMBING
J 0
(-3225 1550);
DISPLAY 0.872340 (-3225 1550);
PAINT GREEN (-3225 1550);
DISPLAY INVISIBLE (-3225 1550);
FORCEPROP 1 LAST HDL_TAP TRUE
J 0
(-2900 1375);
DISPLAY 0.872340 (-2900 1375);
DISPLAY INVISIBLE (-2900 1375);
FORCEPROP 1 LAST PATH I243
J 0
(-3227 1500);
DISPLAY 0.872340 (-3227 1500);
PAINT GREEN (-3227 1500);
DISPLAY INVISIBLE (-3227 1500);
FORCEADD TAP..1
R 2
(-5650 5900);
FORCEPROP 3 LASTPIN (-5600 5900) SIG_NAME M_K_CPU1_SA_DQS_DP<0>
J 0
(-5590 5910);
DISPLAY 0.659574 (-5590 5910);
PAINT MONO (-5590 5910);
DISPLAY INVISIBLE (-5590 5910);
FORCEPROP 1 LASTPIN (-5600 5900) BN 0
J 2
(-5588 5908);
DISPLAY 0.489362 (-5588 5908);
PAINT GREEN (-5588 5908);
FORCEPROP 2 LAST CDS_LIB mstr_standard
J 2
(-5650 5900);
DISPLAY 0.723404 (-5650 5900);
PAINT MONO (-5650 5900);
DISPLAY INVISIBLE (-5650 5900);
FORCEPROP 1 LAST BODY_TYPE PLUMBING
J 2
(-5650 5950);
DISPLAY 0.872340 (-5650 5950);
PAINT GREEN (-5650 5950);
DISPLAY INVISIBLE (-5650 5950);
FORCEPROP 1 LAST HDL_TAP TRUE
J 2
(-5975 5775);
DISPLAY 0.872340 (-5975 5775);
DISPLAY INVISIBLE (-5975 5775);
FORCEPROP 1 LAST PATH I244
J 2
(-5648 5900);
DISPLAY 0.872340 (-5648 5900);
PAINT GREEN (-5648 5900);
DISPLAY INVISIBLE (-5648 5900);
FORCEADD TAP..1
R 2
(-5650 5800);
FORCEPROP 3 LASTPIN (-5600 5800) SIG_NAME M_K_CPU1_SA_DQS_DP<1>
J 0
(-5590 5810);
DISPLAY 0.659574 (-5590 5810);
PAINT MONO (-5590 5810);
DISPLAY INVISIBLE (-5590 5810);
FORCEPROP 1 LASTPIN (-5600 5800) BN 1
J 2
(-5588 5808);
DISPLAY 0.489362 (-5588 5808);
PAINT GREEN (-5588 5808);
FORCEPROP 2 LAST CDS_LIB mstr_standard
J 2
(-5650 5800);
DISPLAY 0.723404 (-5650 5800);
PAINT MONO (-5650 5800);
DISPLAY INVISIBLE (-5650 5800);
FORCEPROP 1 LAST BODY_TYPE PLUMBING
J 2
(-5650 5850);
DISPLAY 0.872340 (-5650 5850);
PAINT GREEN (-5650 5850);
DISPLAY INVISIBLE (-5650 5850);
FORCEPROP 1 LAST HDL_TAP TRUE
J 2
(-5975 5675);
DISPLAY 0.872340 (-5975 5675);
DISPLAY INVISIBLE (-5975 5675);
FORCEPROP 1 LAST PATH I245
J 2
(-5648 5800);
DISPLAY 0.872340 (-5648 5800);
PAINT GREEN (-5648 5800);
DISPLAY INVISIBLE (-5648 5800);
FORCEADD TAP..1
R 2
(-5650 5700);
FORCEPROP 3 LASTPIN (-5600 5700) SIG_NAME M_K_CPU1_SA_DQS_DP<2>
J 0
(-5590 5710);
DISPLAY 0.659574 (-5590 5710);
PAINT MONO (-5590 5710);
DISPLAY INVISIBLE (-5590 5710);
FORCEPROP 1 LASTPIN (-5600 5700) BN 2
J 2
(-5588 5708);
DISPLAY 0.489362 (-5588 5708);
PAINT GREEN (-5588 5708);
FORCEPROP 2 LAST CDS_LIB mstr_standard
J 2
(-5650 5700);
DISPLAY 0.723404 (-5650 5700);
PAINT MONO (-5650 5700);
DISPLAY INVISIBLE (-5650 5700);
FORCEPROP 1 LAST BODY_TYPE PLUMBING
J 2
(-5650 5750);
DISPLAY 0.872340 (-5650 5750);
PAINT GREEN (-5650 5750);
DISPLAY INVISIBLE (-5650 5750);
FORCEPROP 1 LAST HDL_TAP TRUE
J 2
(-5975 5575);
DISPLAY 0.872340 (-5975 5575);
DISPLAY INVISIBLE (-5975 5575);
FORCEPROP 1 LAST PATH I246
J 2
(-5648 5700);
DISPLAY 0.872340 (-5648 5700);
PAINT GREEN (-5648 5700);
DISPLAY INVISIBLE (-5648 5700);
FORCEADD TAP..1
R 2
(-5650 5600);
FORCEPROP 3 LASTPIN (-5600 5600) SIG_NAME M_K_CPU1_SA_DQS_DP<3>
J 0
(-5590 5610);
DISPLAY 0.659574 (-5590 5610);
PAINT MONO (-5590 5610);
DISPLAY INVISIBLE (-5590 5610);
FORCEPROP 1 LASTPIN (-5600 5600) BN 3
J 2
(-5588 5608);
DISPLAY 0.489362 (-5588 5608);
PAINT GREEN (-5588 5608);
FORCEPROP 2 LAST CDS_LIB mstr_standard
J 2
(-5650 5600);
DISPLAY 0.723404 (-5650 5600);
PAINT MONO (-5650 5600);
DISPLAY INVISIBLE (-5650 5600);
FORCEPROP 1 LAST BODY_TYPE PLUMBING
J 2
(-5650 5650);
DISPLAY 0.872340 (-5650 5650);
PAINT GREEN (-5650 5650);
DISPLAY INVISIBLE (-5650 5650);
FORCEPROP 1 LAST HDL_TAP TRUE
J 2
(-5975 5475);
DISPLAY 0.872340 (-5975 5475);
DISPLAY INVISIBLE (-5975 5475);
FORCEPROP 1 LAST PATH I247
J 2
(-5648 5600);
DISPLAY 0.872340 (-5648 5600);
PAINT GREEN (-5648 5600);
DISPLAY INVISIBLE (-5648 5600);
FORCEADD TAP..1
R 2
(-5650 5400);
FORCEPROP 3 LASTPIN (-5600 5400) SIG_NAME M_K_CPU1_SA_DQS_DP<5>
J 0
(-5590 5410);
DISPLAY 0.659574 (-5590 5410);
PAINT MONO (-5590 5410);
DISPLAY INVISIBLE (-5590 5410);
FORCEPROP 1 LASTPIN (-5600 5400) BN 5
J 2
(-5588 5408);
DISPLAY 0.489362 (-5588 5408);
PAINT GREEN (-5588 5408);
FORCEPROP 2 LAST CDS_LIB mstr_standard
J 2
(-5650 5400);
DISPLAY 0.723404 (-5650 5400);
PAINT MONO (-5650 5400);
DISPLAY INVISIBLE (-5650 5400);
FORCEPROP 1 LAST BODY_TYPE PLUMBING
J 2
(-5650 5450);
DISPLAY 0.872340 (-5650 5450);
PAINT GREEN (-5650 5450);
DISPLAY INVISIBLE (-5650 5450);
FORCEPROP 1 LAST HDL_TAP TRUE
J 2
(-5975 5275);
DISPLAY 0.872340 (-5975 5275);
DISPLAY INVISIBLE (-5975 5275);
FORCEPROP 1 LAST PATH I248
J 2
(-5648 5400);
DISPLAY 0.872340 (-5648 5400);
PAINT GREEN (-5648 5400);
DISPLAY INVISIBLE (-5648 5400);
FORCEADD TAP..1
R 2
(-5650 5500);
FORCEPROP 3 LASTPIN (-5600 5500) SIG_NAME M_K_CPU1_SA_DQS_DP<4>
J 0
(-5590 5510);
DISPLAY 0.659574 (-5590 5510);
PAINT MONO (-5590 5510);
DISPLAY INVISIBLE (-5590 5510);
FORCEPROP 1 LASTPIN (-5600 5500) BN 4
J 2
(-5588 5508);
DISPLAY 0.489362 (-5588 5508);
PAINT GREEN (-5588 5508);
FORCEPROP 2 LAST CDS_LIB mstr_standard
J 2
(-5650 5500);
DISPLAY 0.723404 (-5650 5500);
PAINT MONO (-5650 5500);
DISPLAY INVISIBLE (-5650 5500);
FORCEPROP 1 LAST BODY_TYPE PLUMBING
J 2
(-5650 5550);
DISPLAY 0.872340 (-5650 5550);
PAINT GREEN (-5650 5550);
DISPLAY INVISIBLE (-5650 5550);
FORCEPROP 1 LAST HDL_TAP TRUE
J 2
(-5975 5375);
DISPLAY 0.872340 (-5975 5375);
DISPLAY INVISIBLE (-5975 5375);
FORCEPROP 1 LAST PATH I249
J 2
(-5648 5500);
DISPLAY 0.872340 (-5648 5500);
PAINT GREEN (-5648 5500);
DISPLAY INVISIBLE (-5648 5500);
FORCEADD TAP..1
R 2
(-5650 5300);
FORCEPROP 3 LASTPIN (-5600 5300) SIG_NAME M_K_CPU1_SA_DQS_DP<6>
J 0
(-5590 5310);
DISPLAY 0.659574 (-5590 5310);
PAINT MONO (-5590 5310);
DISPLAY INVISIBLE (-5590 5310);
FORCEPROP 1 LASTPIN (-5600 5300) BN 6
J 2
(-5588 5308);
DISPLAY 0.489362 (-5588 5308);
PAINT GREEN (-5588 5308);
FORCEPROP 2 LAST CDS_LIB mstr_standard
J 2
(-5650 5300);
DISPLAY 0.723404 (-5650 5300);
PAINT MONO (-5650 5300);
DISPLAY INVISIBLE (-5650 5300);
FORCEPROP 1 LAST BODY_TYPE PLUMBING
J 2
(-5650 5350);
DISPLAY 0.872340 (-5650 5350);
PAINT GREEN (-5650 5350);
DISPLAY INVISIBLE (-5650 5350);
FORCEPROP 1 LAST HDL_TAP TRUE
J 2
(-5975 5175);
DISPLAY 0.872340 (-5975 5175);
DISPLAY INVISIBLE (-5975 5175);
FORCEPROP 1 LAST PATH I250
J 2
(-5648 5300);
DISPLAY 0.872340 (-5648 5300);
PAINT GREEN (-5648 5300);
DISPLAY INVISIBLE (-5648 5300);
FORCEADD TAP..1
R 2
(-5650 5200);
FORCEPROP 3 LASTPIN (-5600 5200) SIG_NAME M_K_CPU1_SA_DQS_DP<7>
J 0
(-5590 5210);
DISPLAY 0.659574 (-5590 5210);
PAINT MONO (-5590 5210);
DISPLAY INVISIBLE (-5590 5210);
FORCEPROP 1 LASTPIN (-5600 5200) BN 7
J 2
(-5588 5208);
DISPLAY 0.489362 (-5588 5208);
PAINT GREEN (-5588 5208);
FORCEPROP 2 LAST CDS_LIB mstr_standard
J 2
(-5650 5200);
DISPLAY 0.723404 (-5650 5200);
PAINT MONO (-5650 5200);
DISPLAY INVISIBLE (-5650 5200);
FORCEPROP 1 LAST BODY_TYPE PLUMBING
J 2
(-5650 5250);
DISPLAY 0.872340 (-5650 5250);
PAINT GREEN (-5650 5250);
DISPLAY INVISIBLE (-5650 5250);
FORCEPROP 1 LAST HDL_TAP TRUE
J 2
(-5975 5075);
DISPLAY 0.872340 (-5975 5075);
DISPLAY INVISIBLE (-5975 5075);
FORCEPROP 1 LAST PATH I251
J 2
(-5648 5200);
DISPLAY 0.872340 (-5648 5200);
PAINT GREEN (-5648 5200);
DISPLAY INVISIBLE (-5648 5200);
FORCEADD TAP..1
R 2
(-5850 5750);
FORCEPROP 3 LASTPIN (-5800 5750) SIG_NAME M_K_CPU1_SA_DQS_DN<1>
J 0
(-5790 5760);
DISPLAY 0.659574 (-5790 5760);
PAINT MONO (-5790 5760);
DISPLAY INVISIBLE (-5790 5760);
FORCEPROP 1 LASTPIN (-5800 5750) BN 1
J 2
(-5788 5758);
DISPLAY 0.489362 (-5788 5758);
PAINT GREEN (-5788 5758);
FORCEPROP 2 LAST CDS_LIB mstr_standard
J 2
(-5850 5750);
DISPLAY 0.723404 (-5850 5750);
PAINT MONO (-5850 5750);
DISPLAY INVISIBLE (-5850 5750);
FORCEPROP 1 LAST BODY_TYPE PLUMBING
J 2
(-5850 5800);
DISPLAY 0.872340 (-5850 5800);
PAINT GREEN (-5850 5800);
DISPLAY INVISIBLE (-5850 5800);
FORCEPROP 1 LAST HDL_TAP TRUE
J 2
(-6175 5625);
DISPLAY 0.872340 (-6175 5625);
DISPLAY INVISIBLE (-6175 5625);
FORCEPROP 1 LAST PATH I252
J 2
(-5848 5750);
DISPLAY 0.872340 (-5848 5750);
PAINT GREEN (-5848 5750);
DISPLAY INVISIBLE (-5848 5750);
FORCEADD TAP..1
R 2
(-5850 5850);
FORCEPROP 3 LASTPIN (-5800 5850) SIG_NAME M_K_CPU1_SA_DQS_DN<0>
J 0
(-5790 5860);
DISPLAY 0.659574 (-5790 5860);
PAINT MONO (-5790 5860);
DISPLAY INVISIBLE (-5790 5860);
FORCEPROP 1 LASTPIN (-5800 5850) BN 0
J 2
(-5788 5858);
DISPLAY 0.489362 (-5788 5858);
PAINT GREEN (-5788 5858);
FORCEPROP 2 LAST CDS_LIB mstr_standard
J 2
(-5850 5850);
DISPLAY 0.723404 (-5850 5850);
PAINT MONO (-5850 5850);
DISPLAY INVISIBLE (-5850 5850);
FORCEPROP 1 LAST BODY_TYPE PLUMBING
J 2
(-5850 5900);
DISPLAY 0.872340 (-5850 5900);
PAINT GREEN (-5850 5900);
DISPLAY INVISIBLE (-5850 5900);
FORCEPROP 1 LAST HDL_TAP TRUE
J 2
(-6175 5725);
DISPLAY 0.872340 (-6175 5725);
DISPLAY INVISIBLE (-6175 5725);
FORCEPROP 1 LAST PATH I253
J 2
(-5848 5850);
DISPLAY 0.872340 (-5848 5850);
PAINT GREEN (-5848 5850);
DISPLAY INVISIBLE (-5848 5850);
FORCEADD TAP..1
R 2
(-5850 5650);
FORCEPROP 3 LASTPIN (-5800 5650) SIG_NAME M_K_CPU1_SA_DQS_DN<2>
J 0
(-5790 5660);
DISPLAY 0.659574 (-5790 5660);
PAINT MONO (-5790 5660);
DISPLAY INVISIBLE (-5790 5660);
FORCEPROP 1 LASTPIN (-5800 5650) BN 2
J 2
(-5788 5658);
DISPLAY 0.489362 (-5788 5658);
PAINT GREEN (-5788 5658);
FORCEPROP 2 LAST CDS_LIB mstr_standard
J 2
(-5850 5650);
DISPLAY 0.723404 (-5850 5650);
PAINT MONO (-5850 5650);
DISPLAY INVISIBLE (-5850 5650);
FORCEPROP 1 LAST BODY_TYPE PLUMBING
J 2
(-5850 5700);
DISPLAY 0.872340 (-5850 5700);
PAINT GREEN (-5850 5700);
DISPLAY INVISIBLE (-5850 5700);
FORCEPROP 1 LAST HDL_TAP TRUE
J 2
(-6175 5525);
DISPLAY 0.872340 (-6175 5525);
DISPLAY INVISIBLE (-6175 5525);
FORCEPROP 1 LAST PATH I254
J 2
(-5848 5650);
DISPLAY 0.872340 (-5848 5650);
PAINT GREEN (-5848 5650);
DISPLAY INVISIBLE (-5848 5650);
FORCEADD TAP..1
R 2
(-5850 5550);
FORCEPROP 3 LASTPIN (-5800 5550) SIG_NAME M_K_CPU1_SA_DQS_DN<3>
J 0
(-5790 5560);
DISPLAY 0.659574 (-5790 5560);
PAINT MONO (-5790 5560);
DISPLAY INVISIBLE (-5790 5560);
FORCEPROP 1 LASTPIN (-5800 5550) BN 3
J 2
(-5788 5558);
DISPLAY 0.489362 (-5788 5558);
PAINT GREEN (-5788 5558);
FORCEPROP 2 LAST CDS_LIB mstr_standard
J 2
(-5850 5550);
DISPLAY 0.723404 (-5850 5550);
PAINT MONO (-5850 5550);
DISPLAY INVISIBLE (-5850 5550);
FORCEPROP 1 LAST BODY_TYPE PLUMBING
J 2
(-5850 5600);
DISPLAY 0.872340 (-5850 5600);
PAINT GREEN (-5850 5600);
DISPLAY INVISIBLE (-5850 5600);
FORCEPROP 1 LAST HDL_TAP TRUE
J 2
(-6175 5425);
DISPLAY 0.872340 (-6175 5425);
DISPLAY INVISIBLE (-6175 5425);
FORCEPROP 1 LAST PATH I255
J 2
(-5848 5550);
DISPLAY 0.872340 (-5848 5550);
PAINT GREEN (-5848 5550);
DISPLAY INVISIBLE (-5848 5550);
FORCEADD TAP..1
R 2
(-5850 5450);
FORCEPROP 3 LASTPIN (-5800 5450) SIG_NAME M_K_CPU1_SA_DQS_DN<4>
J 0
(-5790 5460);
DISPLAY 0.659574 (-5790 5460);
PAINT MONO (-5790 5460);
DISPLAY INVISIBLE (-5790 5460);
FORCEPROP 1 LASTPIN (-5800 5450) BN 4
J 2
(-5788 5458);
DISPLAY 0.489362 (-5788 5458);
PAINT GREEN (-5788 5458);
FORCEPROP 2 LAST CDS_LIB mstr_standard
J 2
(-5850 5450);
DISPLAY 0.723404 (-5850 5450);
PAINT MONO (-5850 5450);
DISPLAY INVISIBLE (-5850 5450);
FORCEPROP 1 LAST BODY_TYPE PLUMBING
J 2
(-5850 5500);
DISPLAY 0.872340 (-5850 5500);
PAINT GREEN (-5850 5500);
DISPLAY INVISIBLE (-5850 5500);
FORCEPROP 1 LAST HDL_TAP TRUE
J 2
(-6175 5325);
DISPLAY 0.872340 (-6175 5325);
DISPLAY INVISIBLE (-6175 5325);
FORCEPROP 1 LAST PATH I256
J 2
(-5848 5450);
DISPLAY 0.872340 (-5848 5450);
PAINT GREEN (-5848 5450);
DISPLAY INVISIBLE (-5848 5450);
FORCEADD TAP..1
R 2
(-5850 5350);
FORCEPROP 3 LASTPIN (-5800 5350) SIG_NAME M_K_CPU1_SA_DQS_DN<5>
J 0
(-5790 5360);
DISPLAY 0.659574 (-5790 5360);
PAINT MONO (-5790 5360);
DISPLAY INVISIBLE (-5790 5360);
FORCEPROP 1 LASTPIN (-5800 5350) BN 5
J 2
(-5788 5358);
DISPLAY 0.489362 (-5788 5358);
PAINT GREEN (-5788 5358);
FORCEPROP 2 LAST CDS_LIB mstr_standard
J 2
(-5850 5350);
DISPLAY 0.723404 (-5850 5350);
PAINT MONO (-5850 5350);
DISPLAY INVISIBLE (-5850 5350);
FORCEPROP 1 LAST BODY_TYPE PLUMBING
J 2
(-5850 5400);
DISPLAY 0.872340 (-5850 5400);
PAINT GREEN (-5850 5400);
DISPLAY INVISIBLE (-5850 5400);
FORCEPROP 1 LAST HDL_TAP TRUE
J 2
(-6175 5225);
DISPLAY 0.872340 (-6175 5225);
DISPLAY INVISIBLE (-6175 5225);
FORCEPROP 1 LAST PATH I257
J 2
(-5848 5350);
DISPLAY 0.872340 (-5848 5350);
PAINT GREEN (-5848 5350);
DISPLAY INVISIBLE (-5848 5350);
FORCEADD TAP..1
R 2
(-5850 5250);
FORCEPROP 3 LASTPIN (-5800 5250) SIG_NAME M_K_CPU1_SA_DQS_DN<6>
J 0
(-5790 5260);
DISPLAY 0.659574 (-5790 5260);
PAINT MONO (-5790 5260);
DISPLAY INVISIBLE (-5790 5260);
FORCEPROP 1 LASTPIN (-5800 5250) BN 6
J 2
(-5788 5258);
DISPLAY 0.489362 (-5788 5258);
PAINT GREEN (-5788 5258);
FORCEPROP 2 LAST CDS_LIB mstr_standard
J 2
(-5850 5250);
DISPLAY 0.723404 (-5850 5250);
PAINT MONO (-5850 5250);
DISPLAY INVISIBLE (-5850 5250);
FORCEPROP 1 LAST BODY_TYPE PLUMBING
J 2
(-5850 5300);
DISPLAY 0.872340 (-5850 5300);
PAINT GREEN (-5850 5300);
DISPLAY INVISIBLE (-5850 5300);
FORCEPROP 1 LAST HDL_TAP TRUE
J 2
(-6175 5125);
DISPLAY 0.872340 (-6175 5125);
DISPLAY INVISIBLE (-6175 5125);
FORCEPROP 1 LAST PATH I258
J 2
(-5848 5250);
DISPLAY 0.872340 (-5848 5250);
PAINT GREEN (-5848 5250);
DISPLAY INVISIBLE (-5848 5250);
FORCEADD TAP..1
R 2
(-5850 5150);
FORCEPROP 3 LASTPIN (-5800 5150) SIG_NAME M_K_CPU1_SA_DQS_DN<7>
J 0
(-5790 5160);
DISPLAY 0.659574 (-5790 5160);
PAINT MONO (-5790 5160);
DISPLAY INVISIBLE (-5790 5160);
FORCEPROP 1 LASTPIN (-5800 5150) BN 7
J 2
(-5788 5158);
DISPLAY 0.489362 (-5788 5158);
PAINT GREEN (-5788 5158);
FORCEPROP 2 LAST CDS_LIB mstr_standard
J 2
(-5850 5150);
DISPLAY 0.723404 (-5850 5150);
PAINT MONO (-5850 5150);
DISPLAY INVISIBLE (-5850 5150);
FORCEPROP 1 LAST BODY_TYPE PLUMBING
J 2
(-5850 5200);
DISPLAY 0.872340 (-5850 5200);
PAINT GREEN (-5850 5200);
DISPLAY INVISIBLE (-5850 5200);
FORCEPROP 1 LAST HDL_TAP TRUE
J 2
(-6175 5025);
DISPLAY 0.872340 (-6175 5025);
DISPLAY INVISIBLE (-6175 5025);
FORCEPROP 1 LAST PATH I259
J 2
(-5848 5150);
DISPLAY 0.872340 (-5848 5150);
PAINT GREEN (-5848 5150);
DISPLAY INVISIBLE (-5848 5150);
FORCEADD TAP..1
R 2
(-5650 5100);
FORCEPROP 3 LASTPIN (-5600 5100) SIG_NAME M_K_CPU1_SA_DQS_DP<8>
J 0
(-5590 5110);
DISPLAY 0.659574 (-5590 5110);
PAINT MONO (-5590 5110);
DISPLAY INVISIBLE (-5590 5110);
FORCEPROP 1 LASTPIN (-5600 5100) BN 8
J 2
(-5588 5108);
DISPLAY 0.489362 (-5588 5108);
PAINT GREEN (-5588 5108);
FORCEPROP 2 LAST CDS_LIB mstr_standard
J 2
(-5650 5100);
DISPLAY 0.723404 (-5650 5100);
PAINT MONO (-5650 5100);
DISPLAY INVISIBLE (-5650 5100);
FORCEPROP 1 LAST BODY_TYPE PLUMBING
J 2
(-5650 5150);
DISPLAY 0.872340 (-5650 5150);
PAINT GREEN (-5650 5150);
DISPLAY INVISIBLE (-5650 5150);
FORCEPROP 1 LAST HDL_TAP TRUE
J 2
(-5975 4975);
DISPLAY 0.872340 (-5975 4975);
DISPLAY INVISIBLE (-5975 4975);
FORCEPROP 1 LAST PATH I260
J 2
(-5648 5100);
DISPLAY 0.872340 (-5648 5100);
PAINT GREEN (-5648 5100);
DISPLAY INVISIBLE (-5648 5100);
FORCEADD TAP..1
R 2
(-5650 5000);
FORCEPROP 3 LASTPIN (-5600 5000) SIG_NAME M_K_CPU1_SA_DQS_DP<9>
J 0
(-5590 5010);
DISPLAY 0.659574 (-5590 5010);
PAINT MONO (-5590 5010);
DISPLAY INVISIBLE (-5590 5010);
FORCEPROP 1 LASTPIN (-5600 5000) BN 9
J 2
(-5588 5008);
DISPLAY 0.489362 (-5588 5008);
PAINT GREEN (-5588 5008);
FORCEPROP 2 LAST CDS_LIB mstr_standard
J 2
(-5650 5000);
DISPLAY 0.723404 (-5650 5000);
PAINT MONO (-5650 5000);
DISPLAY INVISIBLE (-5650 5000);
FORCEPROP 1 LAST BODY_TYPE PLUMBING
J 2
(-5650 5050);
DISPLAY 0.872340 (-5650 5050);
PAINT GREEN (-5650 5050);
DISPLAY INVISIBLE (-5650 5050);
FORCEPROP 1 LAST HDL_TAP TRUE
J 2
(-5975 4875);
DISPLAY 0.872340 (-5975 4875);
DISPLAY INVISIBLE (-5975 4875);
FORCEPROP 1 LAST PATH I261
J 2
(-5648 5000);
DISPLAY 0.872340 (-5648 5000);
PAINT GREEN (-5648 5000);
DISPLAY INVISIBLE (-5648 5000);
FORCEADD TAP..1
R 2
(-5650 4850);
FORCEPROP 3 LASTPIN (-5600 4850) SIG_NAME M_K_CPU1_SB_DQS_DP<0>
J 0
(-5590 4860);
DISPLAY 0.659574 (-5590 4860);
PAINT MONO (-5590 4860);
DISPLAY INVISIBLE (-5590 4860);
FORCEPROP 1 LASTPIN (-5600 4850) BN 0
J 2
(-5588 4858);
DISPLAY 0.489362 (-5588 4858);
PAINT GREEN (-5588 4858);
FORCEPROP 2 LAST CDS_LIB mstr_standard
J 2
(-5650 4850);
DISPLAY 0.723404 (-5650 4850);
PAINT MONO (-5650 4850);
DISPLAY INVISIBLE (-5650 4850);
FORCEPROP 1 LAST BODY_TYPE PLUMBING
J 2
(-5650 4900);
DISPLAY 0.872340 (-5650 4900);
PAINT GREEN (-5650 4900);
DISPLAY INVISIBLE (-5650 4900);
FORCEPROP 1 LAST HDL_TAP TRUE
J 2
(-5975 4725);
DISPLAY 0.872340 (-5975 4725);
DISPLAY INVISIBLE (-5975 4725);
FORCEPROP 1 LAST PATH I262
J 2
(-5648 4850);
DISPLAY 0.872340 (-5648 4850);
PAINT GREEN (-5648 4850);
DISPLAY INVISIBLE (-5648 4850);
FORCEADD TAP..1
R 2
(-5650 4750);
FORCEPROP 3 LASTPIN (-5600 4750) SIG_NAME M_K_CPU1_SB_DQS_DP<1>
J 0
(-5590 4760);
DISPLAY 0.659574 (-5590 4760);
PAINT MONO (-5590 4760);
DISPLAY INVISIBLE (-5590 4760);
FORCEPROP 1 LASTPIN (-5600 4750) BN 1
J 2
(-5588 4758);
DISPLAY 0.489362 (-5588 4758);
PAINT GREEN (-5588 4758);
FORCEPROP 2 LAST CDS_LIB mstr_standard
J 2
(-5650 4750);
DISPLAY 0.723404 (-5650 4750);
PAINT MONO (-5650 4750);
DISPLAY INVISIBLE (-5650 4750);
FORCEPROP 1 LAST BODY_TYPE PLUMBING
J 2
(-5650 4800);
DISPLAY 0.872340 (-5650 4800);
PAINT GREEN (-5650 4800);
DISPLAY INVISIBLE (-5650 4800);
FORCEPROP 1 LAST HDL_TAP TRUE
J 2
(-5975 4625);
DISPLAY 0.872340 (-5975 4625);
DISPLAY INVISIBLE (-5975 4625);
FORCEPROP 1 LAST PATH I263
J 2
(-5648 4750);
DISPLAY 0.872340 (-5648 4750);
PAINT GREEN (-5648 4750);
DISPLAY INVISIBLE (-5648 4750);
FORCEADD TAP..1
R 2
(-5650 4650);
FORCEPROP 3 LASTPIN (-5600 4650) SIG_NAME M_K_CPU1_SB_DQS_DP<2>
J 0
(-5590 4660);
DISPLAY 0.659574 (-5590 4660);
PAINT MONO (-5590 4660);
DISPLAY INVISIBLE (-5590 4660);
FORCEPROP 1 LASTPIN (-5600 4650) BN 2
J 2
(-5588 4658);
DISPLAY 0.489362 (-5588 4658);
PAINT GREEN (-5588 4658);
FORCEPROP 2 LAST CDS_LIB mstr_standard
J 2
(-5650 4650);
DISPLAY 0.723404 (-5650 4650);
PAINT MONO (-5650 4650);
DISPLAY INVISIBLE (-5650 4650);
FORCEPROP 1 LAST BODY_TYPE PLUMBING
J 2
(-5650 4700);
DISPLAY 0.872340 (-5650 4700);
PAINT GREEN (-5650 4700);
DISPLAY INVISIBLE (-5650 4700);
FORCEPROP 1 LAST HDL_TAP TRUE
J 2
(-5975 4525);
DISPLAY 0.872340 (-5975 4525);
DISPLAY INVISIBLE (-5975 4525);
FORCEPROP 1 LAST PATH I264
J 2
(-5648 4650);
DISPLAY 0.872340 (-5648 4650);
PAINT GREEN (-5648 4650);
DISPLAY INVISIBLE (-5648 4650);
FORCEADD TAP..1
R 2
(-5650 4550);
FORCEPROP 3 LASTPIN (-5600 4550) SIG_NAME M_K_CPU1_SB_DQS_DP<3>
J 0
(-5590 4560);
DISPLAY 0.659574 (-5590 4560);
PAINT MONO (-5590 4560);
DISPLAY INVISIBLE (-5590 4560);
FORCEPROP 1 LASTPIN (-5600 4550) BN 3
J 2
(-5588 4558);
DISPLAY 0.489362 (-5588 4558);
PAINT GREEN (-5588 4558);
FORCEPROP 2 LAST CDS_LIB mstr_standard
J 2
(-5650 4550);
DISPLAY 0.723404 (-5650 4550);
PAINT MONO (-5650 4550);
DISPLAY INVISIBLE (-5650 4550);
FORCEPROP 1 LAST BODY_TYPE PLUMBING
J 2
(-5650 4600);
DISPLAY 0.872340 (-5650 4600);
PAINT GREEN (-5650 4600);
DISPLAY INVISIBLE (-5650 4600);
FORCEPROP 1 LAST HDL_TAP TRUE
J 2
(-5975 4425);
DISPLAY 0.872340 (-5975 4425);
DISPLAY INVISIBLE (-5975 4425);
FORCEPROP 1 LAST PATH I265
J 2
(-5648 4550);
DISPLAY 0.872340 (-5648 4550);
PAINT GREEN (-5648 4550);
DISPLAY INVISIBLE (-5648 4550);
FORCEADD TAP..1
R 2
(-5650 4450);
FORCEPROP 3 LASTPIN (-5600 4450) SIG_NAME M_K_CPU1_SB_DQS_DP<4>
J 0
(-5590 4460);
DISPLAY 0.659574 (-5590 4460);
PAINT MONO (-5590 4460);
DISPLAY INVISIBLE (-5590 4460);
FORCEPROP 1 LASTPIN (-5600 4450) BN 4
J 2
(-5588 4458);
DISPLAY 0.489362 (-5588 4458);
PAINT GREEN (-5588 4458);
FORCEPROP 2 LAST CDS_LIB mstr_standard
J 2
(-5650 4450);
DISPLAY 0.723404 (-5650 4450);
PAINT MONO (-5650 4450);
DISPLAY INVISIBLE (-5650 4450);
FORCEPROP 1 LAST BODY_TYPE PLUMBING
J 2
(-5650 4500);
DISPLAY 0.872340 (-5650 4500);
PAINT GREEN (-5650 4500);
DISPLAY INVISIBLE (-5650 4500);
FORCEPROP 1 LAST HDL_TAP TRUE
J 2
(-5975 4325);
DISPLAY 0.872340 (-5975 4325);
DISPLAY INVISIBLE (-5975 4325);
FORCEPROP 1 LAST PATH I266
J 2
(-5648 4450);
DISPLAY 0.872340 (-5648 4450);
PAINT GREEN (-5648 4450);
DISPLAY INVISIBLE (-5648 4450);
FORCEADD TAP..1
R 2
(-5650 4250);
FORCEPROP 3 LASTPIN (-5600 4250) SIG_NAME M_K_CPU1_SB_DQS_DP<6>
J 0
(-5590 4260);
DISPLAY 0.659574 (-5590 4260);
PAINT MONO (-5590 4260);
DISPLAY INVISIBLE (-5590 4260);
FORCEPROP 1 LASTPIN (-5600 4250) BN 6
J 2
(-5588 4258);
DISPLAY 0.489362 (-5588 4258);
PAINT GREEN (-5588 4258);
FORCEPROP 2 LAST CDS_LIB mstr_standard
J 2
(-5650 4250);
DISPLAY 0.723404 (-5650 4250);
PAINT MONO (-5650 4250);
DISPLAY INVISIBLE (-5650 4250);
FORCEPROP 1 LAST BODY_TYPE PLUMBING
J 2
(-5650 4300);
DISPLAY 0.872340 (-5650 4300);
PAINT GREEN (-5650 4300);
DISPLAY INVISIBLE (-5650 4300);
FORCEPROP 1 LAST HDL_TAP TRUE
J 2
(-5975 4125);
DISPLAY 0.872340 (-5975 4125);
DISPLAY INVISIBLE (-5975 4125);
FORCEPROP 1 LAST PATH I267
J 2
(-5648 4250);
DISPLAY 0.872340 (-5648 4250);
PAINT GREEN (-5648 4250);
DISPLAY INVISIBLE (-5648 4250);
FORCEADD TAP..1
R 2
(-5650 4350);
FORCEPROP 3 LASTPIN (-5600 4350) SIG_NAME M_K_CPU1_SB_DQS_DP<5>
J 0
(-5590 4360);
DISPLAY 0.659574 (-5590 4360);
PAINT MONO (-5590 4360);
DISPLAY INVISIBLE (-5590 4360);
FORCEPROP 1 LASTPIN (-5600 4350) BN 5
J 2
(-5588 4358);
DISPLAY 0.489362 (-5588 4358);
PAINT GREEN (-5588 4358);
FORCEPROP 2 LAST CDS_LIB mstr_standard
J 2
(-5650 4350);
DISPLAY 0.723404 (-5650 4350);
PAINT MONO (-5650 4350);
DISPLAY INVISIBLE (-5650 4350);
FORCEPROP 1 LAST BODY_TYPE PLUMBING
J 2
(-5650 4400);
DISPLAY 0.872340 (-5650 4400);
PAINT GREEN (-5650 4400);
DISPLAY INVISIBLE (-5650 4400);
FORCEPROP 1 LAST HDL_TAP TRUE
J 2
(-5975 4225);
DISPLAY 0.872340 (-5975 4225);
DISPLAY INVISIBLE (-5975 4225);
FORCEPROP 1 LAST PATH I268
J 2
(-5648 4350);
DISPLAY 0.872340 (-5648 4350);
PAINT GREEN (-5648 4350);
DISPLAY INVISIBLE (-5648 4350);
FORCEADD TAP..1
R 2
(-5650 4150);
FORCEPROP 3 LASTPIN (-5600 4150) SIG_NAME M_K_CPU1_SB_DQS_DP<7>
J 0
(-5590 4160);
DISPLAY 0.659574 (-5590 4160);
PAINT MONO (-5590 4160);
DISPLAY INVISIBLE (-5590 4160);
FORCEPROP 1 LASTPIN (-5600 4150) BN 7
J 2
(-5588 4158);
DISPLAY 0.489362 (-5588 4158);
PAINT GREEN (-5588 4158);
FORCEPROP 2 LAST CDS_LIB mstr_standard
J 2
(-5650 4150);
DISPLAY 0.723404 (-5650 4150);
PAINT MONO (-5650 4150);
DISPLAY INVISIBLE (-5650 4150);
FORCEPROP 1 LAST BODY_TYPE PLUMBING
J 2
(-5650 4200);
DISPLAY 0.872340 (-5650 4200);
PAINT GREEN (-5650 4200);
DISPLAY INVISIBLE (-5650 4200);
FORCEPROP 1 LAST HDL_TAP TRUE
J 2
(-5975 4025);
DISPLAY 0.872340 (-5975 4025);
DISPLAY INVISIBLE (-5975 4025);
FORCEPROP 1 LAST PATH I269
J 2
(-5648 4150);
DISPLAY 0.872340 (-5648 4150);
PAINT GREEN (-5648 4150);
DISPLAY INVISIBLE (-5648 4150);
FORCEADD TAP..1
R 2
(-5850 4950);
FORCEPROP 3 LASTPIN (-5800 4950) SIG_NAME M_K_CPU1_SA_DQS_DN<9>
J 0
(-5790 4960);
DISPLAY 0.659574 (-5790 4960);
PAINT MONO (-5790 4960);
DISPLAY INVISIBLE (-5790 4960);
FORCEPROP 1 LASTPIN (-5800 4950) BN 9
J 2
(-5788 4958);
DISPLAY 0.489362 (-5788 4958);
PAINT GREEN (-5788 4958);
FORCEPROP 2 LAST CDS_LIB mstr_standard
J 2
(-5850 4950);
DISPLAY 0.723404 (-5850 4950);
PAINT MONO (-5850 4950);
DISPLAY INVISIBLE (-5850 4950);
FORCEPROP 1 LAST BODY_TYPE PLUMBING
J 2
(-5850 5000);
DISPLAY 0.872340 (-5850 5000);
PAINT GREEN (-5850 5000);
DISPLAY INVISIBLE (-5850 5000);
FORCEPROP 1 LAST HDL_TAP TRUE
J 2
(-6175 4825);
DISPLAY 0.872340 (-6175 4825);
DISPLAY INVISIBLE (-6175 4825);
FORCEPROP 1 LAST PATH I270
J 2
(-5848 4950);
DISPLAY 0.872340 (-5848 4950);
PAINT GREEN (-5848 4950);
DISPLAY INVISIBLE (-5848 4950);
FORCEADD TAP..1
R 2
(-5850 5050);
FORCEPROP 3 LASTPIN (-5800 5050) SIG_NAME M_K_CPU1_SA_DQS_DN<8>
J 0
(-5790 5060);
DISPLAY 0.659574 (-5790 5060);
PAINT MONO (-5790 5060);
DISPLAY INVISIBLE (-5790 5060);
FORCEPROP 1 LASTPIN (-5800 5050) BN 8
J 2
(-5788 5058);
DISPLAY 0.489362 (-5788 5058);
PAINT GREEN (-5788 5058);
FORCEPROP 2 LAST CDS_LIB mstr_standard
J 2
(-5850 5050);
DISPLAY 0.723404 (-5850 5050);
PAINT MONO (-5850 5050);
DISPLAY INVISIBLE (-5850 5050);
FORCEPROP 1 LAST BODY_TYPE PLUMBING
J 2
(-5850 5100);
DISPLAY 0.872340 (-5850 5100);
PAINT GREEN (-5850 5100);
DISPLAY INVISIBLE (-5850 5100);
FORCEPROP 1 LAST HDL_TAP TRUE
J 2
(-6175 4925);
DISPLAY 0.872340 (-6175 4925);
DISPLAY INVISIBLE (-6175 4925);
FORCEPROP 1 LAST PATH I271
J 2
(-5848 5050);
DISPLAY 0.872340 (-5848 5050);
PAINT GREEN (-5848 5050);
DISPLAY INVISIBLE (-5848 5050);
FORCEADD TAP..1
R 2
(-5850 4800);
FORCEPROP 3 LASTPIN (-5800 4800) SIG_NAME M_K_CPU1_SB_DQS_DN<0>
J 0
(-5790 4810);
DISPLAY 0.659574 (-5790 4810);
PAINT MONO (-5790 4810);
DISPLAY INVISIBLE (-5790 4810);
FORCEPROP 1 LASTPIN (-5800 4800) BN 0
J 2
(-5788 4808);
DISPLAY 0.489362 (-5788 4808);
PAINT GREEN (-5788 4808);
FORCEPROP 2 LAST CDS_LIB mstr_standard
J 2
(-5850 4800);
DISPLAY 0.723404 (-5850 4800);
PAINT MONO (-5850 4800);
DISPLAY INVISIBLE (-5850 4800);
FORCEPROP 1 LAST BODY_TYPE PLUMBING
J 2
(-5850 4850);
DISPLAY 0.872340 (-5850 4850);
PAINT GREEN (-5850 4850);
DISPLAY INVISIBLE (-5850 4850);
FORCEPROP 1 LAST HDL_TAP TRUE
J 2
(-6175 4675);
DISPLAY 0.872340 (-6175 4675);
DISPLAY INVISIBLE (-6175 4675);
FORCEPROP 1 LAST PATH I272
J 2
(-5848 4800);
DISPLAY 0.872340 (-5848 4800);
PAINT GREEN (-5848 4800);
DISPLAY INVISIBLE (-5848 4800);
FORCEADD TAP..1
R 2
(-5850 4700);
FORCEPROP 3 LASTPIN (-5800 4700) SIG_NAME M_K_CPU1_SB_DQS_DN<1>
J 0
(-5790 4710);
DISPLAY 0.659574 (-5790 4710);
PAINT MONO (-5790 4710);
DISPLAY INVISIBLE (-5790 4710);
FORCEPROP 1 LASTPIN (-5800 4700) BN 1
J 2
(-5788 4708);
DISPLAY 0.489362 (-5788 4708);
PAINT GREEN (-5788 4708);
FORCEPROP 2 LAST CDS_LIB mstr_standard
J 2
(-5850 4700);
DISPLAY 0.723404 (-5850 4700);
PAINT MONO (-5850 4700);
DISPLAY INVISIBLE (-5850 4700);
FORCEPROP 1 LAST BODY_TYPE PLUMBING
J 2
(-5850 4750);
DISPLAY 0.872340 (-5850 4750);
PAINT GREEN (-5850 4750);
DISPLAY INVISIBLE (-5850 4750);
FORCEPROP 1 LAST HDL_TAP TRUE
J 2
(-6175 4575);
DISPLAY 0.872340 (-6175 4575);
DISPLAY INVISIBLE (-6175 4575);
FORCEPROP 1 LAST PATH I273
J 2
(-5848 4700);
DISPLAY 0.872340 (-5848 4700);
PAINT GREEN (-5848 4700);
DISPLAY INVISIBLE (-5848 4700);
FORCEADD TAP..1
R 2
(-5850 4600);
FORCEPROP 3 LASTPIN (-5800 4600) SIG_NAME M_K_CPU1_SB_DQS_DN<2>
J 0
(-5790 4610);
DISPLAY 0.659574 (-5790 4610);
PAINT MONO (-5790 4610);
DISPLAY INVISIBLE (-5790 4610);
FORCEPROP 1 LASTPIN (-5800 4600) BN 2
J 2
(-5788 4608);
DISPLAY 0.489362 (-5788 4608);
PAINT GREEN (-5788 4608);
FORCEPROP 2 LAST CDS_LIB mstr_standard
J 2
(-5850 4600);
DISPLAY 0.723404 (-5850 4600);
PAINT MONO (-5850 4600);
DISPLAY INVISIBLE (-5850 4600);
FORCEPROP 1 LAST BODY_TYPE PLUMBING
J 2
(-5850 4650);
DISPLAY 0.872340 (-5850 4650);
PAINT GREEN (-5850 4650);
DISPLAY INVISIBLE (-5850 4650);
FORCEPROP 1 LAST HDL_TAP TRUE
J 2
(-6175 4475);
DISPLAY 0.872340 (-6175 4475);
DISPLAY INVISIBLE (-6175 4475);
FORCEPROP 1 LAST PATH I274
J 2
(-5848 4600);
DISPLAY 0.872340 (-5848 4600);
PAINT GREEN (-5848 4600);
DISPLAY INVISIBLE (-5848 4600);
FORCEADD TAP..1
R 2
(-5850 4500);
FORCEPROP 3 LASTPIN (-5800 4500) SIG_NAME M_K_CPU1_SB_DQS_DN<3>
J 0
(-5790 4510);
DISPLAY 0.659574 (-5790 4510);
PAINT MONO (-5790 4510);
DISPLAY INVISIBLE (-5790 4510);
FORCEPROP 1 LASTPIN (-5800 4500) BN 3
J 2
(-5788 4508);
DISPLAY 0.489362 (-5788 4508);
PAINT GREEN (-5788 4508);
FORCEPROP 2 LAST CDS_LIB mstr_standard
J 2
(-5850 4500);
DISPLAY 0.723404 (-5850 4500);
PAINT MONO (-5850 4500);
DISPLAY INVISIBLE (-5850 4500);
FORCEPROP 1 LAST BODY_TYPE PLUMBING
J 2
(-5850 4550);
DISPLAY 0.872340 (-5850 4550);
PAINT GREEN (-5850 4550);
DISPLAY INVISIBLE (-5850 4550);
FORCEPROP 1 LAST HDL_TAP TRUE
J 2
(-6175 4375);
DISPLAY 0.872340 (-6175 4375);
DISPLAY INVISIBLE (-6175 4375);
FORCEPROP 1 LAST PATH I275
J 2
(-5848 4500);
DISPLAY 0.872340 (-5848 4500);
PAINT GREEN (-5848 4500);
DISPLAY INVISIBLE (-5848 4500);
FORCEADD TAP..1
R 2
(-5850 4400);
FORCEPROP 3 LASTPIN (-5800 4400) SIG_NAME M_K_CPU1_SB_DQS_DN<4>
J 0
(-5790 4410);
DISPLAY 0.659574 (-5790 4410);
PAINT MONO (-5790 4410);
DISPLAY INVISIBLE (-5790 4410);
FORCEPROP 1 LASTPIN (-5800 4400) BN 4
J 2
(-5788 4408);
DISPLAY 0.489362 (-5788 4408);
PAINT GREEN (-5788 4408);
FORCEPROP 2 LAST CDS_LIB mstr_standard
J 2
(-5850 4400);
DISPLAY 0.723404 (-5850 4400);
PAINT MONO (-5850 4400);
DISPLAY INVISIBLE (-5850 4400);
FORCEPROP 1 LAST BODY_TYPE PLUMBING
J 2
(-5850 4450);
DISPLAY 0.872340 (-5850 4450);
PAINT GREEN (-5850 4450);
DISPLAY INVISIBLE (-5850 4450);
FORCEPROP 1 LAST HDL_TAP TRUE
J 2
(-6175 4275);
DISPLAY 0.872340 (-6175 4275);
DISPLAY INVISIBLE (-6175 4275);
FORCEPROP 1 LAST PATH I276
J 2
(-5848 4400);
DISPLAY 0.872340 (-5848 4400);
PAINT GREEN (-5848 4400);
DISPLAY INVISIBLE (-5848 4400);
FORCEADD TAP..1
R 2
(-5850 4200);
FORCEPROP 3 LASTPIN (-5800 4200) SIG_NAME M_K_CPU1_SB_DQS_DN<6>
J 0
(-5790 4210);
DISPLAY 0.659574 (-5790 4210);
PAINT MONO (-5790 4210);
DISPLAY INVISIBLE (-5790 4210);
FORCEPROP 1 LASTPIN (-5800 4200) BN 6
J 2
(-5788 4208);
DISPLAY 0.489362 (-5788 4208);
PAINT GREEN (-5788 4208);
FORCEPROP 2 LAST CDS_LIB mstr_standard
J 2
(-5850 4200);
DISPLAY 0.723404 (-5850 4200);
PAINT MONO (-5850 4200);
DISPLAY INVISIBLE (-5850 4200);
FORCEPROP 1 LAST BODY_TYPE PLUMBING
J 2
(-5850 4250);
DISPLAY 0.872340 (-5850 4250);
PAINT GREEN (-5850 4250);
DISPLAY INVISIBLE (-5850 4250);
FORCEPROP 1 LAST HDL_TAP TRUE
J 2
(-6175 4075);
DISPLAY 0.872340 (-6175 4075);
DISPLAY INVISIBLE (-6175 4075);
FORCEPROP 1 LAST PATH I277
J 2
(-5848 4200);
DISPLAY 0.872340 (-5848 4200);
PAINT GREEN (-5848 4200);
DISPLAY INVISIBLE (-5848 4200);
FORCEADD TAP..1
R 2
(-5850 4300);
FORCEPROP 3 LASTPIN (-5800 4300) SIG_NAME M_K_CPU1_SB_DQS_DN<5>
J 0
(-5790 4310);
DISPLAY 0.659574 (-5790 4310);
PAINT MONO (-5790 4310);
DISPLAY INVISIBLE (-5790 4310);
FORCEPROP 1 LASTPIN (-5800 4300) BN 5
J 2
(-5788 4308);
DISPLAY 0.489362 (-5788 4308);
PAINT GREEN (-5788 4308);
FORCEPROP 2 LAST CDS_LIB mstr_standard
J 2
(-5850 4300);
DISPLAY 0.723404 (-5850 4300);
PAINT MONO (-5850 4300);
DISPLAY INVISIBLE (-5850 4300);
FORCEPROP 1 LAST BODY_TYPE PLUMBING
J 2
(-5850 4350);
DISPLAY 0.872340 (-5850 4350);
PAINT GREEN (-5850 4350);
DISPLAY INVISIBLE (-5850 4350);
FORCEPROP 1 LAST HDL_TAP TRUE
J 2
(-6175 4175);
DISPLAY 0.872340 (-6175 4175);
DISPLAY INVISIBLE (-6175 4175);
FORCEPROP 1 LAST PATH I278
J 2
(-5848 4300);
DISPLAY 0.872340 (-5848 4300);
PAINT GREEN (-5848 4300);
DISPLAY INVISIBLE (-5848 4300);
FORCEADD TAP..1
R 2
(-5850 4100);
FORCEPROP 3 LASTPIN (-5800 4100) SIG_NAME M_K_CPU1_SB_DQS_DN<7>
J 0
(-5790 4110);
DISPLAY 0.659574 (-5790 4110);
PAINT MONO (-5790 4110);
DISPLAY INVISIBLE (-5790 4110);
FORCEPROP 1 LASTPIN (-5800 4100) BN 7
J 2
(-5788 4108);
DISPLAY 0.489362 (-5788 4108);
PAINT GREEN (-5788 4108);
FORCEPROP 2 LAST CDS_LIB mstr_standard
J 2
(-5850 4100);
DISPLAY 0.723404 (-5850 4100);
PAINT MONO (-5850 4100);
DISPLAY INVISIBLE (-5850 4100);
FORCEPROP 1 LAST BODY_TYPE PLUMBING
J 2
(-5850 4150);
DISPLAY 0.872340 (-5850 4150);
PAINT GREEN (-5850 4150);
DISPLAY INVISIBLE (-5850 4150);
FORCEPROP 1 LAST HDL_TAP TRUE
J 2
(-6175 3975);
DISPLAY 0.872340 (-6175 3975);
DISPLAY INVISIBLE (-6175 3975);
FORCEPROP 1 LAST PATH I279
J 2
(-5848 4100);
DISPLAY 0.872340 (-5848 4100);
PAINT GREEN (-5848 4100);
DISPLAY INVISIBLE (-5848 4100);
FORCEADD OFFPAGE..3
R 2
(-6550 5925);
FORCEPROP 2 LAST $XR0 108 
J 0
(-6830 5925);
DISPLAY 0.638298 (-6830 5925);
PAINT MONO (-6830 5925);
FORCEPROP 2 LAST CDS_LIB standard
J 0
(-6550 5925);
DISPLAY INVISIBLE (-6550 5925);
FORCEPROP 1 LAST OFFPAGE TRUE
J 2
(-6875 5800);
DISPLAY 0.872340 (-6875 5800);
PAINT GREEN (-6875 5800);
DISPLAY INVISIBLE (-6875 5800);
FORCEPROP 1 LAST COMMENT_BODY TRUE
J 2
(-6500 5825);
DISPLAY 0.872340 (-6500 5825);
PAINT GREEN (-6500 5825);
DISPLAY INVISIBLE (-6500 5825);
FORCEPROP 2 LAST PATH I280
J 0
(-6825 5975);
DISPLAY 1.021277 (-6825 5975);
DISPLAY INVISIBLE (-6825 5975);
FORCEADD OFFPAGE..3
R 2
(-6550 5875);
FORCEPROP 2 LAST $XR0 108 
J 0
(-6830 5875);
DISPLAY 0.638298 (-6830 5875);
PAINT MONO (-6830 5875);
FORCEPROP 2 LAST CDS_LIB standard
J 0
(-6550 5875);
DISPLAY INVISIBLE (-6550 5875);
FORCEPROP 1 LAST OFFPAGE TRUE
J 2
(-6875 5750);
DISPLAY 0.872340 (-6875 5750);
PAINT GREEN (-6875 5750);
DISPLAY INVISIBLE (-6875 5750);
FORCEPROP 1 LAST COMMENT_BODY TRUE
J 2
(-6500 5775);
DISPLAY 0.872340 (-6500 5775);
PAINT GREEN (-6500 5775);
DISPLAY INVISIBLE (-6500 5775);
FORCEPROP 2 LAST PATH I281
J 0
(-6825 5925);
DISPLAY 1.021277 (-6825 5925);
DISPLAY INVISIBLE (-6825 5925);
FORCEADD OFFPAGE..3
R 2
(-6550 4875);
FORCEPROP 2 LAST $XR0 108 
J 0
(-6830 4875);
DISPLAY 0.638298 (-6830 4875);
PAINT MONO (-6830 4875);
FORCEPROP 2 LAST CDS_LIB standard
J 0
(-6550 4875);
DISPLAY INVISIBLE (-6550 4875);
FORCEPROP 1 LAST OFFPAGE TRUE
J 2
(-6875 4750);
DISPLAY 0.872340 (-6875 4750);
PAINT GREEN (-6875 4750);
DISPLAY INVISIBLE (-6875 4750);
FORCEPROP 1 LAST COMMENT_BODY TRUE
J 2
(-6500 4775);
DISPLAY 0.872340 (-6500 4775);
PAINT GREEN (-6500 4775);
DISPLAY INVISIBLE (-6500 4775);
FORCEPROP 2 LAST PATH I282
J 0
(-6825 4925);
DISPLAY 1.021277 (-6825 4925);
DISPLAY INVISIBLE (-6825 4925);
FORCEADD OFFPAGE..3
R 2
(-6550 4825);
FORCEPROP 2 LAST $XR0 108 
J 0
(-6830 4825);
DISPLAY 0.638298 (-6830 4825);
PAINT MONO (-6830 4825);
FORCEPROP 2 LAST CDS_LIB standard
J 0
(-6550 4825);
DISPLAY INVISIBLE (-6550 4825);
FORCEPROP 1 LAST OFFPAGE TRUE
J 2
(-6875 4700);
DISPLAY 0.872340 (-6875 4700);
PAINT GREEN (-6875 4700);
DISPLAY INVISIBLE (-6875 4700);
FORCEPROP 1 LAST COMMENT_BODY TRUE
J 2
(-6500 4725);
DISPLAY 0.872340 (-6500 4725);
PAINT GREEN (-6500 4725);
DISPLAY INVISIBLE (-6500 4725);
FORCEPROP 2 LAST PATH I283
J 0
(-6825 4875);
DISPLAY 1.021277 (-6825 4875);
DISPLAY INVISIBLE (-6825 4875);
FORCEADD TAP..1
R 2
(-5650 3950);
FORCEPROP 3 LASTPIN (-5600 3950) SIG_NAME M_K_CPU1_SB_DQS_DP<9>
J 0
(-5590 3960);
DISPLAY 0.659574 (-5590 3960);
PAINT MONO (-5590 3960);
DISPLAY INVISIBLE (-5590 3960);
FORCEPROP 1 LASTPIN (-5600 3950) BN 9
J 2
(-5588 3958);
DISPLAY 0.489362 (-5588 3958);
PAINT GREEN (-5588 3958);
FORCEPROP 2 LAST CDS_LIB mstr_standard
J 2
(-5650 3950);
DISPLAY 0.723404 (-5650 3950);
PAINT MONO (-5650 3950);
DISPLAY INVISIBLE (-5650 3950);
FORCEPROP 1 LAST BODY_TYPE PLUMBING
J 2
(-5650 4000);
DISPLAY 0.872340 (-5650 4000);
PAINT GREEN (-5650 4000);
DISPLAY INVISIBLE (-5650 4000);
FORCEPROP 1 LAST HDL_TAP TRUE
J 2
(-5975 3825);
DISPLAY 0.872340 (-5975 3825);
DISPLAY INVISIBLE (-5975 3825);
FORCEPROP 1 LAST PATH I284
J 2
(-5648 3950);
DISPLAY 0.872340 (-5648 3950);
PAINT GREEN (-5648 3950);
DISPLAY INVISIBLE (-5648 3950);
FORCEADD TAP..1
R 2
(-5650 4050);
FORCEPROP 3 LASTPIN (-5600 4050) SIG_NAME M_K_CPU1_SB_DQS_DP<8>
J 0
(-5590 4060);
DISPLAY 0.659574 (-5590 4060);
PAINT MONO (-5590 4060);
DISPLAY INVISIBLE (-5590 4060);
FORCEPROP 1 LASTPIN (-5600 4050) BN 8
J 2
(-5588 4058);
DISPLAY 0.489362 (-5588 4058);
PAINT GREEN (-5588 4058);
FORCEPROP 2 LAST CDS_LIB mstr_standard
J 2
(-5650 4050);
DISPLAY 0.723404 (-5650 4050);
PAINT MONO (-5650 4050);
DISPLAY INVISIBLE (-5650 4050);
FORCEPROP 1 LAST BODY_TYPE PLUMBING
J 2
(-5650 4100);
DISPLAY 0.872340 (-5650 4100);
PAINT GREEN (-5650 4100);
DISPLAY INVISIBLE (-5650 4100);
FORCEPROP 1 LAST HDL_TAP TRUE
J 2
(-5975 3925);
DISPLAY 0.872340 (-5975 3925);
DISPLAY INVISIBLE (-5975 3925);
FORCEPROP 1 LAST PATH I285
J 2
(-5648 4050);
DISPLAY 0.872340 (-5648 4050);
PAINT GREEN (-5648 4050);
DISPLAY INVISIBLE (-5648 4050);
FORCEADD TAP..1
R 2
(-5850 4000);
FORCEPROP 3 LASTPIN (-5800 4000) SIG_NAME M_K_CPU1_SB_DQS_DN<8>
J 0
(-5790 4010);
DISPLAY 0.659574 (-5790 4010);
PAINT MONO (-5790 4010);
DISPLAY INVISIBLE (-5790 4010);
FORCEPROP 1 LASTPIN (-5800 4000) BN 8
J 2
(-5788 4008);
DISPLAY 0.489362 (-5788 4008);
PAINT GREEN (-5788 4008);
FORCEPROP 2 LAST CDS_LIB mstr_standard
J 2
(-5850 4000);
DISPLAY 0.723404 (-5850 4000);
PAINT MONO (-5850 4000);
DISPLAY INVISIBLE (-5850 4000);
FORCEPROP 1 LAST BODY_TYPE PLUMBING
J 2
(-5850 4050);
DISPLAY 0.872340 (-5850 4050);
PAINT GREEN (-5850 4050);
DISPLAY INVISIBLE (-5850 4050);
FORCEPROP 1 LAST HDL_TAP TRUE
J 2
(-6175 3875);
DISPLAY 0.872340 (-6175 3875);
DISPLAY INVISIBLE (-6175 3875);
FORCEPROP 1 LAST PATH I286
J 2
(-5848 4000);
DISPLAY 0.872340 (-5848 4000);
PAINT GREEN (-5848 4000);
DISPLAY INVISIBLE (-5848 4000);
FORCEADD TAP..1
R 2
(-5850 3900);
FORCEPROP 3 LASTPIN (-5800 3900) SIG_NAME M_K_CPU1_SB_DQS_DN<9>
J 0
(-5790 3910);
DISPLAY 0.659574 (-5790 3910);
PAINT MONO (-5790 3910);
DISPLAY INVISIBLE (-5790 3910);
FORCEPROP 1 LASTPIN (-5800 3900) BN 9
J 2
(-5788 3908);
DISPLAY 0.489362 (-5788 3908);
PAINT GREEN (-5788 3908);
FORCEPROP 2 LAST CDS_LIB mstr_standard
J 2
(-5850 3900);
DISPLAY 0.723404 (-5850 3900);
PAINT MONO (-5850 3900);
DISPLAY INVISIBLE (-5850 3900);
FORCEPROP 1 LAST BODY_TYPE PLUMBING
J 2
(-5850 3950);
DISPLAY 0.872340 (-5850 3950);
PAINT GREEN (-5850 3950);
DISPLAY INVISIBLE (-5850 3950);
FORCEPROP 1 LAST HDL_TAP TRUE
J 2
(-6175 3775);
DISPLAY 0.872340 (-6175 3775);
DISPLAY INVISIBLE (-6175 3775);
FORCEPROP 1 LAST PATH I287
J 2
(-5848 3900);
DISPLAY 0.872340 (-5848 3900);
PAINT GREEN (-5848 3900);
DISPLAY INVISIBLE (-5848 3900);
FORCEADD TAP..1
R 2
(-5850 3600);
FORCEPROP 3 LASTPIN (-5800 3600) SIG_NAME M_K_CPU1_SA_CA<3>
J 0
(-5790 3610);
DISPLAY 0.659574 (-5790 3610);
PAINT MONO (-5790 3610);
DISPLAY INVISIBLE (-5790 3610);
FORCEPROP 1 LASTPIN (-5800 3600) BN 3
J 2
(-5788 3608);
DISPLAY 0.489362 (-5788 3608);
PAINT GREEN (-5788 3608);
FORCEPROP 2 LAST CDS_LIB mstr_standard
J 0
(-5850 3600);
DISPLAY 0.723404 (-5850 3600);
PAINT MONO (-5850 3600);
DISPLAY INVISIBLE (-5850 3600);
FORCEPROP 1 LAST BODY_TYPE PLUMBING
J 2
(-5850 3650);
DISPLAY 0.872340 (-5850 3650);
PAINT GREEN (-5850 3650);
DISPLAY INVISIBLE (-5850 3650);
FORCEPROP 1 LAST HDL_TAP TRUE
J 2
(-6175 3475);
DISPLAY 0.872340 (-6175 3475);
DISPLAY INVISIBLE (-6175 3475);
FORCEPROP 1 LAST PATH I288
J 2
(-5848 3600);
DISPLAY 0.872340 (-5848 3600);
PAINT GREEN (-5848 3600);
DISPLAY INVISIBLE (-5848 3600);
FORCEADD TAP..1
R 2
(-5850 3750);
FORCEPROP 3 LASTPIN (-5800 3750) SIG_NAME M_K_CPU1_SA_CA<0>
J 0
(-5790 3760);
DISPLAY 0.659574 (-5790 3760);
PAINT MONO (-5790 3760);
DISPLAY INVISIBLE (-5790 3760);
FORCEPROP 1 LASTPIN (-5800 3750) BN 0
J 2
(-5788 3758);
DISPLAY 0.489362 (-5788 3758);
PAINT GREEN (-5788 3758);
FORCEPROP 2 LAST CDS_LIB mstr_standard
J 0
(-5850 3750);
DISPLAY 0.723404 (-5850 3750);
PAINT MONO (-5850 3750);
DISPLAY INVISIBLE (-5850 3750);
FORCEPROP 1 LAST BODY_TYPE PLUMBING
J 2
(-5850 3800);
DISPLAY 0.872340 (-5850 3800);
PAINT GREEN (-5850 3800);
DISPLAY INVISIBLE (-5850 3800);
FORCEPROP 1 LAST HDL_TAP TRUE
J 2
(-6175 3625);
DISPLAY 0.872340 (-6175 3625);
DISPLAY INVISIBLE (-6175 3625);
FORCEPROP 1 LAST PATH I289
J 2
(-5848 3750);
DISPLAY 0.872340 (-5848 3750);
PAINT GREEN (-5848 3750);
DISPLAY INVISIBLE (-5848 3750);
FORCEADD TAP..1
R 2
(-5850 3700);
FORCEPROP 3 LASTPIN (-5800 3700) SIG_NAME M_K_CPU1_SA_CA<1>
J 0
(-5790 3710);
DISPLAY 0.659574 (-5790 3710);
PAINT MONO (-5790 3710);
DISPLAY INVISIBLE (-5790 3710);
FORCEPROP 1 LASTPIN (-5800 3700) BN 1
J 2
(-5788 3708);
DISPLAY 0.489362 (-5788 3708);
PAINT GREEN (-5788 3708);
FORCEPROP 2 LAST CDS_LIB mstr_standard
J 0
(-5850 3700);
DISPLAY 0.723404 (-5850 3700);
PAINT MONO (-5850 3700);
DISPLAY INVISIBLE (-5850 3700);
FORCEPROP 1 LAST BODY_TYPE PLUMBING
J 2
(-5850 3750);
DISPLAY 0.872340 (-5850 3750);
PAINT GREEN (-5850 3750);
DISPLAY INVISIBLE (-5850 3750);
FORCEPROP 1 LAST HDL_TAP TRUE
J 2
(-6175 3575);
DISPLAY 0.872340 (-6175 3575);
DISPLAY INVISIBLE (-6175 3575);
FORCEPROP 1 LAST PATH I290
J 2
(-5848 3700);
DISPLAY 0.872340 (-5848 3700);
PAINT GREEN (-5848 3700);
DISPLAY INVISIBLE (-5848 3700);
FORCEADD TAP..1
R 2
(-5850 3650);
FORCEPROP 3 LASTPIN (-5800 3650) SIG_NAME M_K_CPU1_SA_CA<2>
J 0
(-5790 3660);
DISPLAY 0.659574 (-5790 3660);
PAINT MONO (-5790 3660);
DISPLAY INVISIBLE (-5790 3660);
FORCEPROP 1 LASTPIN (-5800 3650) BN 2
J 2
(-5788 3658);
DISPLAY 0.489362 (-5788 3658);
PAINT GREEN (-5788 3658);
FORCEPROP 2 LAST CDS_LIB mstr_standard
J 0
(-5850 3650);
DISPLAY 0.723404 (-5850 3650);
PAINT MONO (-5850 3650);
DISPLAY INVISIBLE (-5850 3650);
FORCEPROP 1 LAST BODY_TYPE PLUMBING
J 2
(-5850 3700);
DISPLAY 0.872340 (-5850 3700);
PAINT GREEN (-5850 3700);
DISPLAY INVISIBLE (-5850 3700);
FORCEPROP 1 LAST HDL_TAP TRUE
J 2
(-6175 3525);
DISPLAY 0.872340 (-6175 3525);
DISPLAY INVISIBLE (-6175 3525);
FORCEPROP 1 LAST PATH I291
J 2
(-5848 3650);
DISPLAY 0.872340 (-5848 3650);
PAINT GREEN (-5848 3650);
DISPLAY INVISIBLE (-5848 3650);
FORCEADD TAP..1
R 2
(-5850 3350);
FORCEPROP 3 LASTPIN (-5800 3350) SIG_NAME M_K_CPU1_SB_CA<0>
J 0
(-5790 3360);
DISPLAY 0.659574 (-5790 3360);
PAINT MONO (-5790 3360);
DISPLAY INVISIBLE (-5790 3360);
FORCEPROP 1 LASTPIN (-5800 3350) BN 0
J 2
(-5788 3358);
DISPLAY 0.489362 (-5788 3358);
PAINT GREEN (-5788 3358);
FORCEPROP 2 LAST CDS_LIB mstr_standard
J 0
(-5850 3350);
DISPLAY 0.723404 (-5850 3350);
PAINT MONO (-5850 3350);
DISPLAY INVISIBLE (-5850 3350);
FORCEPROP 1 LAST BODY_TYPE PLUMBING
J 2
(-5850 3400);
DISPLAY 0.872340 (-5850 3400);
PAINT GREEN (-5850 3400);
DISPLAY INVISIBLE (-5850 3400);
FORCEPROP 1 LAST HDL_TAP TRUE
J 2
(-6175 3225);
DISPLAY 0.872340 (-6175 3225);
DISPLAY INVISIBLE (-6175 3225);
FORCEPROP 1 LAST PATH I292
J 2
(-5848 3350);
DISPLAY 0.872340 (-5848 3350);
PAINT GREEN (-5848 3350);
DISPLAY INVISIBLE (-5848 3350);
FORCEADD TAP..1
R 2
(-5850 3550);
FORCEPROP 3 LASTPIN (-5800 3550) SIG_NAME M_K_CPU1_SA_CA<4>
J 0
(-5790 3560);
DISPLAY 0.659574 (-5790 3560);
PAINT MONO (-5790 3560);
DISPLAY INVISIBLE (-5790 3560);
FORCEPROP 1 LASTPIN (-5800 3550) BN 4
J 2
(-5788 3558);
DISPLAY 0.489362 (-5788 3558);
PAINT GREEN (-5788 3558);
FORCEPROP 2 LAST CDS_LIB mstr_standard
J 0
(-5850 3550);
DISPLAY 0.723404 (-5850 3550);
PAINT MONO (-5850 3550);
DISPLAY INVISIBLE (-5850 3550);
FORCEPROP 1 LAST BODY_TYPE PLUMBING
J 2
(-5850 3600);
DISPLAY 0.872340 (-5850 3600);
PAINT GREEN (-5850 3600);
DISPLAY INVISIBLE (-5850 3600);
FORCEPROP 1 LAST HDL_TAP TRUE
J 2
(-6175 3425);
DISPLAY 0.872340 (-6175 3425);
DISPLAY INVISIBLE (-6175 3425);
FORCEPROP 1 LAST PATH I293
J 2
(-5848 3550);
DISPLAY 0.872340 (-5848 3550);
PAINT GREEN (-5848 3550);
DISPLAY INVISIBLE (-5848 3550);
FORCEADD TAP..1
R 2
(-5850 3450);
FORCEPROP 3 LASTPIN (-5800 3450) SIG_NAME M_K_CPU1_SA_CA<6>
J 0
(-5790 3460);
DISPLAY 0.659574 (-5790 3460);
PAINT MONO (-5790 3460);
DISPLAY INVISIBLE (-5790 3460);
FORCEPROP 1 LASTPIN (-5800 3450) BN 6
J 2
(-5788 3458);
DISPLAY 0.489362 (-5788 3458);
PAINT GREEN (-5788 3458);
FORCEPROP 2 LAST CDS_LIB mstr_standard
J 0
(-5850 3450);
DISPLAY 0.723404 (-5850 3450);
PAINT MONO (-5850 3450);
DISPLAY INVISIBLE (-5850 3450);
FORCEPROP 1 LAST BODY_TYPE PLUMBING
J 2
(-5850 3500);
DISPLAY 0.872340 (-5850 3500);
PAINT GREEN (-5850 3500);
DISPLAY INVISIBLE (-5850 3500);
FORCEPROP 1 LAST HDL_TAP TRUE
J 2
(-6175 3325);
DISPLAY 0.872340 (-6175 3325);
DISPLAY INVISIBLE (-6175 3325);
FORCEPROP 1 LAST PATH I294
J 2
(-5848 3450);
DISPLAY 0.872340 (-5848 3450);
PAINT GREEN (-5848 3450);
DISPLAY INVISIBLE (-5848 3450);
FORCEADD TAP..1
R 2
(-5850 3500);
FORCEPROP 3 LASTPIN (-5800 3500) SIG_NAME M_K_CPU1_SA_CA<5>
J 0
(-5790 3510);
DISPLAY 0.659574 (-5790 3510);
PAINT MONO (-5790 3510);
DISPLAY INVISIBLE (-5790 3510);
FORCEPROP 1 LASTPIN (-5800 3500) BN 5
J 2
(-5788 3508);
DISPLAY 0.489362 (-5788 3508);
PAINT GREEN (-5788 3508);
FORCEPROP 2 LAST CDS_LIB mstr_standard
J 0
(-5850 3500);
DISPLAY 0.723404 (-5850 3500);
PAINT MONO (-5850 3500);
DISPLAY INVISIBLE (-5850 3500);
FORCEPROP 1 LAST BODY_TYPE PLUMBING
J 2
(-5850 3550);
DISPLAY 0.872340 (-5850 3550);
PAINT GREEN (-5850 3550);
DISPLAY INVISIBLE (-5850 3550);
FORCEPROP 1 LAST HDL_TAP TRUE
J 2
(-6175 3375);
DISPLAY 0.872340 (-6175 3375);
DISPLAY INVISIBLE (-6175 3375);
FORCEPROP 1 LAST PATH I295
J 2
(-5848 3500);
DISPLAY 0.872340 (-5848 3500);
PAINT GREEN (-5848 3500);
DISPLAY INVISIBLE (-5848 3500);
FORCEADD TAP..1
R 2
(-5850 3250);
FORCEPROP 3 LASTPIN (-5800 3250) SIG_NAME M_K_CPU1_SB_CA<2>
J 0
(-5790 3260);
DISPLAY 0.659574 (-5790 3260);
PAINT MONO (-5790 3260);
DISPLAY INVISIBLE (-5790 3260);
FORCEPROP 1 LASTPIN (-5800 3250) BN 2
J 2
(-5788 3258);
DISPLAY 0.489362 (-5788 3258);
PAINT GREEN (-5788 3258);
FORCEPROP 2 LAST CDS_LIB mstr_standard
J 0
(-5850 3250);
DISPLAY 0.723404 (-5850 3250);
PAINT MONO (-5850 3250);
DISPLAY INVISIBLE (-5850 3250);
FORCEPROP 1 LAST BODY_TYPE PLUMBING
J 2
(-5850 3300);
DISPLAY 0.872340 (-5850 3300);
PAINT GREEN (-5850 3300);
DISPLAY INVISIBLE (-5850 3300);
FORCEPROP 1 LAST HDL_TAP TRUE
J 2
(-6175 3125);
DISPLAY 0.872340 (-6175 3125);
DISPLAY INVISIBLE (-6175 3125);
FORCEPROP 1 LAST PATH I296
J 2
(-5848 3250);
DISPLAY 0.872340 (-5848 3250);
PAINT GREEN (-5848 3250);
DISPLAY INVISIBLE (-5848 3250);
FORCEADD TAP..1
R 2
(-5850 3300);
FORCEPROP 3 LASTPIN (-5800 3300) SIG_NAME M_K_CPU1_SB_CA<1>
J 0
(-5790 3310);
DISPLAY 0.659574 (-5790 3310);
PAINT MONO (-5790 3310);
DISPLAY INVISIBLE (-5790 3310);
FORCEPROP 1 LASTPIN (-5800 3300) BN 1
J 2
(-5788 3308);
DISPLAY 0.489362 (-5788 3308);
PAINT GREEN (-5788 3308);
FORCEPROP 2 LAST CDS_LIB mstr_standard
J 0
(-5850 3300);
DISPLAY 0.723404 (-5850 3300);
PAINT MONO (-5850 3300);
DISPLAY INVISIBLE (-5850 3300);
FORCEPROP 1 LAST BODY_TYPE PLUMBING
J 2
(-5850 3350);
DISPLAY 0.872340 (-5850 3350);
PAINT GREEN (-5850 3350);
DISPLAY INVISIBLE (-5850 3350);
FORCEPROP 1 LAST HDL_TAP TRUE
J 2
(-6175 3175);
DISPLAY 0.872340 (-6175 3175);
DISPLAY INVISIBLE (-6175 3175);
FORCEPROP 1 LAST PATH I297
J 2
(-5848 3300);
DISPLAY 0.872340 (-5848 3300);
PAINT GREEN (-5848 3300);
DISPLAY INVISIBLE (-5848 3300);
FORCEADD TAP..1
R 2
(-5850 3200);
FORCEPROP 3 LASTPIN (-5800 3200) SIG_NAME M_K_CPU1_SB_CA<3>
J 0
(-5790 3210);
DISPLAY 0.659574 (-5790 3210);
PAINT MONO (-5790 3210);
DISPLAY INVISIBLE (-5790 3210);
FORCEPROP 1 LASTPIN (-5800 3200) BN 3
J 2
(-5788 3208);
DISPLAY 0.489362 (-5788 3208);
PAINT GREEN (-5788 3208);
FORCEPROP 2 LAST CDS_LIB mstr_standard
J 0
(-5850 3200);
DISPLAY 0.723404 (-5850 3200);
PAINT MONO (-5850 3200);
DISPLAY INVISIBLE (-5850 3200);
FORCEPROP 1 LAST BODY_TYPE PLUMBING
J 2
(-5850 3250);
DISPLAY 0.872340 (-5850 3250);
PAINT GREEN (-5850 3250);
DISPLAY INVISIBLE (-5850 3250);
FORCEPROP 1 LAST HDL_TAP TRUE
J 2
(-6175 3075);
DISPLAY 0.872340 (-6175 3075);
DISPLAY INVISIBLE (-6175 3075);
FORCEPROP 1 LAST PATH I298
J 2
(-5848 3200);
DISPLAY 0.872340 (-5848 3200);
PAINT GREEN (-5848 3200);
DISPLAY INVISIBLE (-5848 3200);
FORCEADD TAP..1
R 2
(-5850 3150);
FORCEPROP 3 LASTPIN (-5800 3150) SIG_NAME M_K_CPU1_SB_CA<4>
J 0
(-5790 3160);
DISPLAY 0.659574 (-5790 3160);
PAINT MONO (-5790 3160);
DISPLAY INVISIBLE (-5790 3160);
FORCEPROP 1 LASTPIN (-5800 3150) BN 4
J 2
(-5788 3158);
DISPLAY 0.489362 (-5788 3158);
PAINT GREEN (-5788 3158);
FORCEPROP 2 LAST CDS_LIB mstr_standard
J 0
(-5850 3150);
DISPLAY 0.723404 (-5850 3150);
PAINT MONO (-5850 3150);
DISPLAY INVISIBLE (-5850 3150);
FORCEPROP 1 LAST BODY_TYPE PLUMBING
J 2
(-5850 3200);
DISPLAY 0.872340 (-5850 3200);
PAINT GREEN (-5850 3200);
DISPLAY INVISIBLE (-5850 3200);
FORCEPROP 1 LAST HDL_TAP TRUE
J 2
(-6175 3025);
DISPLAY 0.872340 (-6175 3025);
DISPLAY INVISIBLE (-6175 3025);
FORCEPROP 1 LAST PATH I299
J 2
(-5848 3150);
DISPLAY 0.872340 (-5848 3150);
PAINT GREEN (-5848 3150);
DISPLAY INVISIBLE (-5848 3150);
FORCEADD TAP..1
R 2
(-5850 3100);
FORCEPROP 3 LASTPIN (-5800 3100) SIG_NAME M_K_CPU1_SB_CA<5>
J 0
(-5790 3110);
DISPLAY 0.659574 (-5790 3110);
PAINT MONO (-5790 3110);
DISPLAY INVISIBLE (-5790 3110);
FORCEPROP 1 LASTPIN (-5800 3100) BN 5
J 2
(-5788 3108);
DISPLAY 0.489362 (-5788 3108);
PAINT GREEN (-5788 3108);
FORCEPROP 2 LAST CDS_LIB mstr_standard
J 0
(-5850 3100);
DISPLAY 0.723404 (-5850 3100);
PAINT MONO (-5850 3100);
DISPLAY INVISIBLE (-5850 3100);
FORCEPROP 1 LAST BODY_TYPE PLUMBING
J 2
(-5850 3150);
DISPLAY 0.872340 (-5850 3150);
PAINT GREEN (-5850 3150);
DISPLAY INVISIBLE (-5850 3150);
FORCEPROP 1 LAST HDL_TAP TRUE
J 2
(-6175 2975);
DISPLAY 0.872340 (-6175 2975);
DISPLAY INVISIBLE (-6175 2975);
FORCEPROP 1 LAST PATH I300
J 2
(-5848 3100);
DISPLAY 0.872340 (-5848 3100);
PAINT GREEN (-5848 3100);
DISPLAY INVISIBLE (-5848 3100);
FORCEADD TAP..1
R 2
(-5850 3050);
FORCEPROP 3 LASTPIN (-5800 3050) SIG_NAME M_K_CPU1_SB_CA<6>
J 0
(-5790 3060);
DISPLAY 0.659574 (-5790 3060);
PAINT MONO (-5790 3060);
DISPLAY INVISIBLE (-5790 3060);
FORCEPROP 1 LASTPIN (-5800 3050) BN 6
J 2
(-5788 3058);
DISPLAY 0.489362 (-5788 3058);
PAINT GREEN (-5788 3058);
FORCEPROP 2 LAST CDS_LIB mstr_standard
J 0
(-5850 3050);
DISPLAY 0.723404 (-5850 3050);
PAINT MONO (-5850 3050);
DISPLAY INVISIBLE (-5850 3050);
FORCEPROP 1 LAST BODY_TYPE PLUMBING
J 2
(-5850 3100);
DISPLAY 0.872340 (-5850 3100);
PAINT GREEN (-5850 3100);
DISPLAY INVISIBLE (-5850 3100);
FORCEPROP 1 LAST HDL_TAP TRUE
J 2
(-6175 2925);
DISPLAY 0.872340 (-6175 2925);
DISPLAY INVISIBLE (-6175 2925);
FORCEPROP 1 LAST PATH I301
J 2
(-5848 3050);
DISPLAY 0.872340 (-5848 3050);
PAINT GREEN (-5848 3050);
DISPLAY INVISIBLE (-5848 3050);
FORCEADD OFFPAGE..2
R 2
(-6450 3775);
FORCEPROP 2 LAST $XR0 108 
J 0
(-6705 3775);
DISPLAY 0.638298 (-6705 3775);
PAINT MONO (-6705 3775);
FORCEPROP 2 LAST CDS_LIB standard
J 0
(-6450 3775);
DISPLAY INVISIBLE (-6450 3775);
FORCEPROP 1 LAST OFFPAGE TRUE
J 2
(-6775 3650);
DISPLAY 0.872340 (-6775 3650);
PAINT GREEN (-6775 3650);
DISPLAY INVISIBLE (-6775 3650);
FORCEPROP 1 LAST COMMENT_BODY TRUE
J 2
(-6405 3680);
DISPLAY 0.872340 (-6405 3680);
PAINT GREEN (-6405 3680);
DISPLAY INVISIBLE (-6405 3680);
FORCEPROP 2 LAST PATH I302
J 0
(-6700 3825);
DISPLAY 1.021277 (-6700 3825);
DISPLAY INVISIBLE (-6700 3825);
FORCEADD OFFPAGE..2
R 2
(-6450 3375);
FORCEPROP 2 LAST $XR0 108 
J 0
(-6705 3375);
DISPLAY 0.638298 (-6705 3375);
PAINT MONO (-6705 3375);
FORCEPROP 2 LAST CDS_LIB standard
J 0
(-6450 3375);
DISPLAY INVISIBLE (-6450 3375);
FORCEPROP 1 LAST OFFPAGE TRUE
J 2
(-6775 3250);
DISPLAY 0.872340 (-6775 3250);
PAINT GREEN (-6775 3250);
DISPLAY INVISIBLE (-6775 3250);
FORCEPROP 1 LAST COMMENT_BODY TRUE
J 2
(-6405 3280);
DISPLAY 0.872340 (-6405 3280);
PAINT GREEN (-6405 3280);
DISPLAY INVISIBLE (-6405 3280);
FORCEPROP 2 LAST PATH I303
J 0
(-6700 3425);
DISPLAY 1.021277 (-6700 3425);
DISPLAY INVISIBLE (-6700 3425);
FORCEADD OFFPAGE..2
R 2
(-6450 2850);
FORCEPROP 2 LAST $XR0 108 
J 0
(-6705 2850);
DISPLAY 0.638298 (-6705 2850);
PAINT MONO (-6705 2850);
FORCEPROP 2 LAST CDS_LIB standard
J 0
(-6450 2850);
DISPLAY INVISIBLE (-6450 2850);
FORCEPROP 1 LAST OFFPAGE TRUE
J 2
(-6775 2725);
DISPLAY 0.872340 (-6775 2725);
PAINT GREEN (-6775 2725);
DISPLAY INVISIBLE (-6775 2725);
FORCEPROP 1 LAST COMMENT_BODY TRUE
J 2
(-6405 2755);
DISPLAY 0.872340 (-6405 2755);
PAINT GREEN (-6405 2755);
DISPLAY INVISIBLE (-6405 2755);
FORCEPROP 2 LAST PATH I304
J 0
(-6700 2900);
DISPLAY 1.021277 (-6700 2900);
DISPLAY INVISIBLE (-6700 2900);
FORCEADD OFFPAGE..2
R 2
(-6450 2900);
FORCEPROP 2 LAST $XR0 108 
J 0
(-6705 2900);
DISPLAY 0.638298 (-6705 2900);
PAINT MONO (-6705 2900);
FORCEPROP 2 LAST CDS_LIB standard
J 0
(-6450 2900);
DISPLAY INVISIBLE (-6450 2900);
FORCEPROP 1 LAST OFFPAGE TRUE
J 2
(-6775 2775);
DISPLAY 0.872340 (-6775 2775);
PAINT GREEN (-6775 2775);
DISPLAY INVISIBLE (-6775 2775);
FORCEPROP 1 LAST COMMENT_BODY TRUE
J 2
(-6405 2805);
DISPLAY 0.872340 (-6405 2805);
PAINT GREEN (-6405 2805);
DISPLAY INVISIBLE (-6405 2805);
FORCEPROP 2 LAST PATH I305
J 0
(-6700 2950);
DISPLAY 1.021277 (-6700 2950);
DISPLAY INVISIBLE (-6700 2950);
FORCEADD OFFPAGE..2
R 2
(-6450 2750);
FORCEPROP 2 LAST $XR0 108 
J 0
(-6705 2750);
DISPLAY 0.638298 (-6705 2750);
PAINT MONO (-6705 2750);
FORCEPROP 2 LAST CDS_LIB standard
J 0
(-6450 2750);
DISPLAY INVISIBLE (-6450 2750);
FORCEPROP 1 LAST OFFPAGE TRUE
J 2
(-6775 2625);
DISPLAY 0.872340 (-6775 2625);
PAINT GREEN (-6775 2625);
DISPLAY INVISIBLE (-6775 2625);
FORCEPROP 1 LAST COMMENT_BODY TRUE
J 2
(-6405 2655);
DISPLAY 0.872340 (-6405 2655);
PAINT GREEN (-6405 2655);
DISPLAY INVISIBLE (-6405 2655);
FORCEPROP 2 LAST PATH I306
J 0
(-6700 2800);
DISPLAY 1.021277 (-6700 2800);
DISPLAY INVISIBLE (-6700 2800);
FORCEADD OFFPAGE..2
R 2
(-6450 2700);
FORCEPROP 2 LAST $XR0 108 
J 0
(-6705 2700);
DISPLAY 0.638298 (-6705 2700);
PAINT MONO (-6705 2700);
FORCEPROP 2 LAST CDS_LIB standard
J 0
(-6450 2700);
DISPLAY INVISIBLE (-6450 2700);
FORCEPROP 1 LAST OFFPAGE TRUE
J 2
(-6775 2575);
DISPLAY 0.872340 (-6775 2575);
PAINT GREEN (-6775 2575);
DISPLAY INVISIBLE (-6775 2575);
FORCEPROP 1 LAST COMMENT_BODY TRUE
J 2
(-6405 2605);
DISPLAY 0.872340 (-6405 2605);
PAINT GREEN (-6405 2605);
DISPLAY INVISIBLE (-6405 2605);
FORCEPROP 2 LAST PATH I307
J 0
(-6700 2750);
DISPLAY 1.021277 (-6700 2750);
DISPLAY INVISIBLE (-6700 2750);
FORCEADD OFFPAGE..1
(-6450 2600);
FORCEPROP 2 LAST $XR0 108 
J 0
(-6732 2600);
DISPLAY 0.638298 (-6732 2600);
PAINT MONO (-6732 2600);
FORCEPROP 2 LAST CDS_LIB standard
J 0
(-6450 2600);
DISPLAY INVISIBLE (-6450 2600);
FORCEPROP 1 LAST OFFPAGE TRUE
J 0
(-6125 2475);
DISPLAY 0.872340 (-6125 2475);
PAINT GREEN (-6125 2475);
DISPLAY INVISIBLE (-6125 2475);
FORCEPROP 1 LAST COMMENT_BODY TRUE
J 0
(-6325 2500);
DISPLAY 0.872340 (-6325 2500);
PAINT GREEN (-6325 2500);
DISPLAY INVISIBLE (-6325 2500);
FORCEPROP 2 LAST PATH I308
J 0
(-6725 2650);
DISPLAY 1.021277 (-6725 2650);
DISPLAY INVISIBLE (-6725 2650);
FORCEADD OFFPAGE..5
(-6450 2500);
FORCEPROP 2 LAST $XR0 108 
J 0
(-6705 2500);
DISPLAY 0.638298 (-6705 2500);
PAINT MONO (-6705 2500);
FORCEPROP 2 LAST CDS_LIB mstr_standard
J 0
(-6450 2500);
DISPLAY INVISIBLE (-6450 2500);
FORCEPROP 1 LAST OFFPAGE TRUE
J 0
(-6125 2375);
DISPLAY 0.872340 (-6125 2375);
PAINT GREEN (-6125 2375);
DISPLAY INVISIBLE (-6125 2375);
FORCEPROP 1 LAST COMMENT_BODY TRUE
J 0
(-6350 2425);
DISPLAY 0.872340 (-6350 2425);
PAINT GREEN (-6350 2425);
DISPLAY INVISIBLE (-6350 2425);
FORCEPROP 2 LAST PATH I309
J 0
(-6700 2550);
DISPLAY 1.021277 (-6700 2550);
DISPLAY INVISIBLE (-6700 2550);
FORCEADD OFFPAGE..2
R 2
(-6450 2400);
FORCEPROP 2 LAST $XR0 108 
J 0
(-6705 2400);
DISPLAY 0.638298 (-6705 2400);
PAINT MONO (-6705 2400);
FORCEPROP 2 LAST CDS_LIB standard
J 0
(-6450 2400);
DISPLAY INVISIBLE (-6450 2400);
FORCEPROP 1 LAST OFFPAGE TRUE
J 2
(-6775 2275);
DISPLAY 0.872340 (-6775 2275);
PAINT GREEN (-6775 2275);
DISPLAY INVISIBLE (-6775 2275);
FORCEPROP 1 LAST COMMENT_BODY TRUE
J 2
(-6405 2305);
DISPLAY 0.872340 (-6405 2305);
PAINT GREEN (-6405 2305);
DISPLAY INVISIBLE (-6405 2305);
FORCEPROP 2 LAST PATH I310
J 0
(-6700 2450);
DISPLAY 1.021277 (-6700 2450);
DISPLAY INVISIBLE (-6700 2450);
FORCEADD OFFPAGE..2
R 2
(-6450 2350);
FORCEPROP 2 LAST $XR0 108 
J 0
(-6705 2350);
DISPLAY 0.638298 (-6705 2350);
PAINT MONO (-6705 2350);
FORCEPROP 2 LAST CDS_LIB standard
J 0
(-6450 2350);
DISPLAY INVISIBLE (-6450 2350);
FORCEPROP 1 LAST OFFPAGE TRUE
J 2
(-6775 2225);
DISPLAY 0.872340 (-6775 2225);
PAINT GREEN (-6775 2225);
DISPLAY INVISIBLE (-6775 2225);
FORCEPROP 1 LAST COMMENT_BODY TRUE
J 2
(-6405 2255);
DISPLAY 0.872340 (-6405 2255);
PAINT GREEN (-6405 2255);
DISPLAY INVISIBLE (-6405 2255);
FORCEPROP 2 LAST PATH I311
J 0
(-6700 2400);
DISPLAY 1.021277 (-6700 2400);
DISPLAY INVISIBLE (-6700 2400);
FORCEADD OFFPAGE..1
(-6450 2250);
FORCEPROP 2 LAST $XR0 108 
J 0
(-6732 2250);
DISPLAY 0.638298 (-6732 2250);
PAINT MONO (-6732 2250);
FORCEPROP 2 LAST CDS_LIB standard
J 0
(-6450 2250);
DISPLAY INVISIBLE (-6450 2250);
FORCEPROP 1 LAST OFFPAGE TRUE
J 0
(-6125 2125);
DISPLAY 0.872340 (-6125 2125);
PAINT GREEN (-6125 2125);
DISPLAY INVISIBLE (-6125 2125);
FORCEPROP 1 LAST COMMENT_BODY TRUE
J 0
(-6325 2150);
DISPLAY 0.872340 (-6325 2150);
PAINT GREEN (-6325 2150);
DISPLAY INVISIBLE (-6325 2150);
FORCEPROP 2 LAST PATH I312
J 0
(-6725 2300);
DISPLAY 1.021277 (-6725 2300);
DISPLAY INVISIBLE (-6725 2300);
FORCEADD OFFPAGE..5
(-6450 2150);
FORCEPROP 2 LAST $XR0 108 
J 0
(-6705 2150);
DISPLAY 0.638298 (-6705 2150);
PAINT MONO (-6705 2150);
FORCEPROP 2 LAST CDS_LIB standard
J 0
(-6450 2150);
DISPLAY INVISIBLE (-6450 2150);
FORCEPROP 1 LAST OFFPAGE TRUE
J 0
(-6125 2025);
DISPLAY 0.872340 (-6125 2025);
PAINT GREEN (-6125 2025);
DISPLAY INVISIBLE (-6125 2025);
FORCEPROP 1 LAST COMMENT_BODY TRUE
J 0
(-6350 2075);
DISPLAY 0.872340 (-6350 2075);
PAINT GREEN (-6350 2075);
DISPLAY INVISIBLE (-6350 2075);
FORCEPROP 2 LAST PATH I313
J 0
(-6700 2200);
DISPLAY 1.021277 (-6700 2200);
DISPLAY INVISIBLE (-6700 2200);
FORCEADD Q_RES..1
(-6525 2050);
FORCEPROP 1 LAST LOCATION R510
J 0
(-6850 2050);
DISPLAY 0.489362 (-6850 2050);
PAINT SKYBLUE (-6850 2050);
FORCEPROP 0 LAST $SEC 1
J 0
(-6700 2100);
DISPLAY 0.680851 (-6700 2100);
PAINT MONO (-6700 2100);
DISPLAY INVISIBLE (-6700 2100);
FORCEPROP 0 LAST CDS_SEC 1
J 0
(-6700 2100);
DISPLAY 1.021277 (-6700 2100);
DISPLAY INVISIBLE (-6700 2100);
FORCEPROP 1 LASTPIN (-6625 2050) $PN 1
J 0
(-6613 2062);
DISPLAY 0.489362 (-6613 2062);
PAINT MONO (-6613 2062);
FORCEPROP 1 LASTPIN (-6425 2050) $PN 2
J 0
(-6463 2062);
DISPLAY 0.489362 (-6463 2062);
PAINT MONO (-6463 2062);
FORCEPROP 1 LAST PACK_TYPE 0402LF
J 0
(-6850 2025);
DISPLAY 0.489362 (-6850 2025);
PAINT SKYBLUE (-6850 2025);
FORCEPROP 1 LAST TOLERANCE 1%
J 0
(-6250 2050);
DISPLAY 0.489362 (-6250 2050);
PAINT SKYBLUE (-6250 2050);
FORCEPROP 1 LAST VALUE 15
J 2
(-6200 2050);
DISPLAY 0.489362 (-6200 2050);
PAINT SKYBLUE (-6200 2050);
FORCEPROP 1 LAST MATERIAL CHIP
J 0
(-6650 2175);
DISPLAY 0.638298 (-6650 2175);
PAINT SKYBLUE (-6650 2175);
DISPLAY INVISIBLE (-6650 2175);
FORCEPROP 1 LAST WATTAGE 1/16W
J 2
(-6300 2175);
DISPLAY 0.638298 (-6300 2175);
PAINT SKYBLUE (-6300 2175);
DISPLAY INVISIBLE (-6300 2175);
FORCEPROP 2 LAST CDS_LIB pure_quanta
J 0
(-6525 2050);
DISPLAY INVISIBLE (-6525 2050);
FORCEPROP 1 LAST PATH I314
J 0
(-6575 2200);
DISPLAY 0.978723 (-6575 2200);
PAINT WHITE (-6575 2200);
DISPLAY INVISIBLE (-6575 2200);
FORCEPROP 1 LAST PART_NUMBER CS01502FB03
J 0
(-6400 2025);
DISPLAY 0.489362 (-6400 2025);
PAINT SKYBLUE (-6400 2025);
DISPLAY INVISIBLE (-6400 2025);
FORCEADD OFFPAGE..5
(-6450 1950);
FORCEPROP 2 LAST $XR0 108 
J 0
(-6705 1950);
DISPLAY 0.638298 (-6705 1950);
PAINT MONO (-6705 1950);
FORCEPROP 2 LAST CDS_LIB standard
J 0
(-6450 1950);
DISPLAY INVISIBLE (-6450 1950);
FORCEPROP 1 LAST OFFPAGE TRUE
J 0
(-6125 1825);
DISPLAY 0.872340 (-6125 1825);
PAINT GREEN (-6125 1825);
DISPLAY INVISIBLE (-6125 1825);
FORCEPROP 1 LAST COMMENT_BODY TRUE
J 0
(-6350 1875);
DISPLAY 0.872340 (-6350 1875);
PAINT GREEN (-6350 1875);
DISPLAY INVISIBLE (-6350 1875);
FORCEPROP 2 LAST PATH I315
J 0
(-6700 2000);
DISPLAY 1.021277 (-6700 2000);
DISPLAY INVISIBLE (-6700 2000);
FORCEADD OFFPAGE..1
(-7400 2050);
FORCEPROP 2 LAST $XR0 108 
J 0
(-7652 2050);
DISPLAY 0.638298 (-7652 2050);
PAINT MONO (-7652 2050);
FORCEPROP 2 LAST CDS_LIB mstr_standard
J 0
(-7400 2050);
DISPLAY INVISIBLE (-7400 2050);
FORCEPROP 1 LAST OFFPAGE TRUE
J 0
(-7075 1925);
DISPLAY 0.872340 (-7075 1925);
PAINT GREEN (-7075 1925);
DISPLAY INVISIBLE (-7075 1925);
FORCEPROP 1 LAST COMMENT_BODY TRUE
J 0
(-7275 1950);
DISPLAY 0.872340 (-7275 1950);
PAINT GREEN (-7275 1950);
DISPLAY INVISIBLE (-7275 1950);
FORCEPROP 2 LAST PATH I316
J 0
(-7650 2100);
DISPLAY 1.021277 (-7650 2100);
DISPLAY INVISIBLE (-7650 2100);
FORCEADD CAD_NOTE..1
(-7575 2350);
FORCEPROP 0 LAST L1 R1956 PLACE CLOSE TO CPU < 25MM
J 0
(-7725 2225);
DISPLAY 0.617021 (-7725 2225);
PAINT WHITE (-7725 2225);
FORCEPROP 2 LAST CDS_LIB pure_quanta_power
J 0
(-7575 2350);
DISPLAY INVISIBLE (-7575 2350);
FORCEPROP 1 LAST COMMENT_BODY TRUE
J 0
(-7550 2450);
DISPLAY 0.574468 (-7550 2450);
PAINT WHITE (-7550 2450);
DISPLAY INVISIBLE (-7550 2450);
FORCEADD QUANTA_TITLE_BLOCK_C..1
(0 0);
FORCEPROP 0 LAST CDS_CON_LAST_MODIFIED Thu Sep 14 16:11:58 2023
J 0
(-1885 15);
DISPLAY INVISIBLE (-1885 15);
FORCEPROP 1 LAST CUSTOM_TXT_CDS <CON_LAST_MODIFIED>
J 0
(-1885 15);
DISPLAY 0.978723 (-1885 15);
FORCEPROP 2 LAST CUSTOM_TXT_CDS <XR_PAGE_TITLE>
J 0
(-7890 5250);
DISPLAY 0.638298 (-7890 5250);
PAINT PINK (-7890 5250);
DISPLAY INVISIBLE (-7890 5250);
FORCEPROP 1 LAST CUSTOM_TXT_CDS <NAME_2>
J 0
(-3175 50);
FORCEPROP 1 LAST CUSTOM_TXT_CDS <NAME_1>
J 0
(-3175 175);
FORCEPROP 1 LAST CUSTOM_TXT_CDS <Q_NUMBER>
J 0
(-1403 103);
DISPLAY 1.212766 (-1403 103);
FORCEPROP 1 LAST CUSTOM_TXT_CDS <Q_PROJ>
J 0
(-2382 102);
DISPLAY 1.212766 (-2382 102);
FORCEPROP 1 LAST CUSTOM_TXT_CDS <Q_REV>
J 0
(-184 103);
DISPLAY 1.212766 (-184 103);
FORCEPROP 1 LAST CUSTOM_TXT_CDS <CON_PAGE_NUM> OF <CON_TOTAL_PAGES>
J 0
(-446 18);
DISPLAY 0.978723 (-446 18);
FORCEPROP 1 LAST Q_TITLE CPU1 DDR CHK
J 0
(-9366 26);
DISPLAY 2.446809 (-9366 26);
PAINT GREEN (-9366 26);
FORCEPROP 2 LAST PAGE_BORDER TRUE
J 0
(-7890 5250);
DISPLAY 0.638298 (-7890 5250);
PAINT PINK (-7890 5250);
DISPLAY INVISIBLE (-7890 5250);
FORCEPROP 1 LAST CDS_LMAN_SYM_OUTLINE -9475,6775,100,-125
J 0
(0 0);
DISPLAY 0.468085 (0 0);
PAINT GREEN (0 0);
DISPLAY INVISIBLE (0 0);
FORCEPROP 2 LAST CDS_LIB pure_quanta
J 0
(0 0);
DISPLAY INVISIBLE (0 0);
FORCEPROP 2 LAST CDS_XR_PAGE_TITLE CR-47 : @T6G_MB_LIB.T6G(SCH_1):PAGE47
J 0
(-7890 5250);
DISPLAY 0.638298 (-7890 5250);
PAINT PINK (-7890 5250);
DISPLAY INVISIBLE (-7890 5250);
FORCEPROP 1 LAST Q_DEPT BU9
J 1
(-3763 49);
DISPLAY 1.957447 (-3763 49);
PAINT GREEN (-3763 49);
DISPLAY INVISIBLE (-3763 49);
FORCEPROP 1 LAST COMMENT_BODY TRUE
J 0
(12 -13);
DISPLAY 0.978723 (12 -13);
PAINT GREEN (12 -13);
DISPLAY INVISIBLE (12 -13);
WIRE 17 -1 (-3175 5425)(-3175 5375);
WIRE 17 -1 (-3175 5475)(-3175 5425);
WIRE 17 -1 (-3175 5375)(-3175 5325);
WIRE 17 -1 (-3175 5325)(-3175 5275);
WIRE 17 -1 (-3175 5575)(-3175 5475);
WIRE 17 -1 (-3175 5625)(-3175 5575);
WIRE 17 -1 (-3175 5275)(-3175 5225);
WIRE 17 -1 (-3175 5225)(-3175 5175);
WIRE 17 -1 (-3175 5675)(-3175 5625);
WIRE 17 -1 (-3175 5725)(-3175 5675);
WIRE 17 -1 (-3175 5175)(-3175 5125);
WIRE 17 -1 (-3175 5025)(-3175 5125);
WIRE 17 -1 (-3175 5775)(-3175 5725);
WIRE 17 -1 (-3175 5825)(-3175 5775);
WIRE 17 -1 (-3175 4975)(-3175 5025);
WIRE 17 -1 (-3175 4925)(-3175 4975);
WIRE 17 -1 (-3175 5875)(-3175 5825);
WIRE 17 -1 (-3175 5925)(-3175 5875);
WIRE 17 -1 (-3175 4875)(-3175 4925);
WIRE 17 -1 (-3175 4875)(-3175 4825);
WIRE 17 -1 (-3175 5925)(-2550 5925);
FORCEPROP 2 LAST SIG_NAME M_K_CPU1_SA_DQ<31:0>
J 2
(-2610 5935);
DISPLAY 0.489362 (-2610 5935);
WIRE 17 -1 (-3175 4825)(-3175 4775);
WIRE 17 -1 (-3175 4775)(-3175 4725);
WIRE 17 -1 (-3175 4725)(-3175 4675);
WIRE 17 -1 (-3175 4675)(-3175 4575);
WIRE 17 -1 (-3175 4575)(-3175 4525);
WIRE 17 -1 (-3175 4525)(-3175 4475);
WIRE 17 -1 (-3175 4475)(-3175 4425);
WIRE 17 -1 (-3175 4375)(-3175 4425);
WIRE 17 -1 (-3175 4275)(-3175 4325);
WIRE 17 -1 (-3175 4225)(-3175 4275);
WIRE 17 -1 (-3175 4325)(-3175 4375);
WIRE 17 -1 (-3175 4125)(-2550 4125);
FORCEPROP 2 LAST SIG_NAME M_K_CPU1_SB_DQ<31:0>
J 2
(-2610 4135);
DISPLAY 0.489362 (-2610 4135);
WIRE 17 -1 (-3175 3625)(-3175 3575);
WIRE 17 -1 (-3175 3675)(-3175 3625);
WIRE 17 -1 (-3175 3575)(-3175 3525);
WIRE 17 -1 (-3175 3525)(-3175 3475);
WIRE 17 -1 (-3175 3775)(-3175 3675);
WIRE 17 -1 (-3175 3825)(-3175 3775);
WIRE 17 -1 (-3175 3475)(-3175 3425);
WIRE 17 -1 (-3175 3425)(-3175 3375);
WIRE 17 -1 (-3175 3875)(-3175 3825);
WIRE 17 -1 (-3175 3925)(-3175 3875);
WIRE 17 -1 (-3175 3375)(-3175 3325);
WIRE 17 -1 (-3175 3225)(-3175 3325);
WIRE 17 -1 (-3175 3975)(-3175 3925);
WIRE 17 -1 (-3175 4025)(-3175 3975);
WIRE 17 -1 (-3175 3175)(-3175 3225);
WIRE 17 -1 (-3175 3125)(-3175 3175);
WIRE 17 -1 (-3175 4075)(-3175 4025);
WIRE 17 -1 (-3175 4125)(-3175 4075);
WIRE 17 -1 (-3175 3075)(-3175 3125);
WIRE 17 -1 (-3175 3075)(-3175 3025);
WIRE 17 -1 (-3175 3025)(-3175 2975);
WIRE 17 -1 (-3175 2975)(-3175 2925);
WIRE 17 -1 (-3175 2925)(-3175 2875);
WIRE 17 -1 (-3175 2875)(-3175 2775);
WIRE 17 -1 (-3175 2775)(-3175 2725);
WIRE 17 -1 (-3175 2725)(-3175 2675);
WIRE 17 -1 (-3175 2675)(-3175 2625);
WIRE 17 -1 (-3175 2575)(-3175 2625);
WIRE 17 -1 (-3175 2525)(-3175 2575);
WIRE 17 -1 (-3175 2475)(-3175 2525);
WIRE 17 -1 (-3175 2425)(-3175 2475);
WIRE 17 -1 (-3175 2325)(-3175 2350);
WIRE 17 -1 (-3175 2325)(-3175 2275);
WIRE 17 -1 (-3175 2350)(-2675 2350);
FORCEPROP 2 LAST SIG_NAME M_K_CPU1_SA_CB<7:0>
J 2
(-2675 2360);
DISPLAY 0.489362 (-2675 2360);
WIRE 17 -1 (-3175 2225)(-3175 2275);
WIRE 17 -1 (-3175 2225)(-3175 2175);
WIRE 17 -1 (-3175 2125)(-3175 2175);
WIRE 17 -1 (-3175 2075)(-3175 2125);
WIRE 17 -1 (-3175 2025)(-3175 2075);
WIRE 17 -1 (-3175 1975)(-3175 2025);
WIRE 17 -1 (-3175 1875)(-3175 1900);
WIRE 17 -1 (-3175 1875)(-3175 1825);
WIRE 17 -1 (-3175 1900)(-2675 1900);
FORCEPROP 2 LAST SIG_NAME M_K_CPU1_SB_CB<7:0>
J 2
(-2675 1910);
DISPLAY 0.489362 (-2675 1910);
WIRE 17 -1 (-3175 1775)(-3175 1825);
WIRE 17 -1 (-3175 1775)(-3175 1725);
WIRE 17 -1 (-3175 1675)(-3175 1725);
WIRE 17 -1 (-3175 1625)(-3175 1675);
WIRE 17 -1 (-3175 1575)(-3175 1625);
WIRE 17 -1 (-3175 1525)(-3175 1575);
WIRE 17 -1 (-5700 5925)(-5700 5825);
WIRE 17 -1 (-5700 5925)(-6500 5925);
FORCEPROP 2 LAST SIG_NAME M_K_CPU1_SA_DQS_DP<9:0>
J 2
(-5935 5935);
DISPLAY 0.489362 (-5935 5935);
WIRE 17 -1 (-5700 5825)(-5700 5725);
WIRE 17 -1 (-5700 5725)(-5700 5625);
WIRE 17 -1 (-5700 5625)(-5700 5525);
WIRE 17 -1 (-5700 5425)(-5700 5525);
WIRE 17 -1 (-5700 5325)(-5700 5425);
WIRE 17 -1 (-5700 5225)(-5700 5325);
WIRE 17 -1 (-5700 5225)(-5700 5125);
WIRE 17 -1 (-5700 5125)(-5700 5025);
WIRE 17 -1 (-5900 5875)(-5900 5775);
FORCEPROP 2 LAST SIG_NAME M_K_CPU1_SA_DQS_DN<9:0>
J 2
(-5935 5885);
DISPLAY 0.489362 (-5935 5885);
WIRE 17 -1 (-5900 5775)(-5900 5675);
WIRE 17 -1 (-5900 5675)(-5900 5575);
WIRE 17 -1 (-5900 5575)(-5900 5475);
WIRE 17 -1 (-5900 5375)(-5900 5475);
WIRE 17 -1 (-5900 5275)(-5900 5375);
WIRE 17 -1 (-5900 5175)(-5900 5275);
WIRE 17 -1 (-5900 5175)(-5900 5075);
WIRE 17 -1 (-5900 5075)(-5900 4975);
WIRE 17 -1 (-5700 4775)(-5700 4675);
WIRE 17 -1 (-5700 4875)(-5700 4775);
WIRE 17 -1 (-5700 4675)(-5700 4575);
WIRE 17 -1 (-5700 4575)(-5700 4475);
WIRE 17 -1 (-5700 4875)(-6500 4875);
FORCEPROP 2 LAST SIG_NAME M_K_CPU1_SB_DQS_DP<9:0>
J 2
(-5935 4885);
DISPLAY 0.489362 (-5935 4885);
WIRE 17 -1 (-5700 4375)(-5700 4475);
WIRE 17 -1 (-5700 4275)(-5700 4375);
WIRE 17 -1 (-5700 4175)(-5700 4275);
WIRE 17 -1 (-5700 4175)(-5700 4075);
WIRE 17 -1 (-5700 4075)(-5700 3975);
WIRE 17 -1 (-5900 4225)(-5900 4325);
WIRE 17 -1 (-5900 4125)(-5900 4225);
WIRE 17 -1 (-5900 4325)(-5900 4425);
WIRE 17 -1 (-5900 4525)(-5900 4425);
WIRE 17 -1 (-5900 4125)(-5900 4025);
WIRE 17 -1 (-5900 4025)(-5900 3925);
WIRE 17 -1 (-5900 4625)(-5900 4525);
WIRE 17 -1 (-5900 4725)(-5900 4625);
WIRE 17 -1 (-5900 4825)(-5900 4725);
FORCEPROP 2 LAST SIG_NAME M_K_CPU1_SB_DQS_DN<9:0>
J 2
(-5935 4835);
DISPLAY 0.489362 (-5935 4835);
WIRE 17 -1 (-5900 3325)(-5900 3375);
WIRE 17 -1 (-5900 3275)(-5900 3325);
WIRE 17 -1 (-5900 3375)(-6400 3375);
FORCEPROP 2 LAST SIG_NAME M_K_CPU1_SB_CA<6:0>
J 0
(-6400 3385);
DISPLAY 0.489362 (-6400 3385);
WIRE 17 -1 (-5900 3675)(-5900 3725);
WIRE 17 -1 (-5900 3625)(-5900 3675);
WIRE 17 -1 (-5900 3725)(-5900 3775);
WIRE 17 -1 (-5900 3775)(-6400 3775);
FORCEPROP 2 LAST SIG_NAME M_K_CPU1_SA_CA<6:0>
J 0
(-6400 3785);
DISPLAY 0.489362 (-6400 3785);
WIRE 17 -1 (-5900 3225)(-5900 3275);
WIRE 17 -1 (-5900 3575)(-5900 3625);
WIRE 17 -1 (-5900 3525)(-5900 3575);
WIRE 17 -1 (-5900 3475)(-5900 3525);
WIRE 17 -1 (-5900 3175)(-5900 3225);
WIRE 17 -1 (-5900 3125)(-5900 3175);
WIRE 17 -1 (-5900 3075)(-5900 3125);
WIRE 17 -1 (-5900 5875)(-6500 5875);
WIRE 17 -1 (-5900 4825)(-6500 4825);
WIRE 16 -1 (-7350 2050)(-6625 2050);
FORCEPROP 2 LAST SIG_NAME M_K_CPU1_ALERT_N
J 0
(-7310 2060);
DISPLAY 0.489362 (-7310 2060);
WIRE 16 -1 (-6425 2050)(-5300 2050);
FORCEPROP 2 LAST SIG_NAME M_K_CPU1_ALERT_R_N
J 0
(-6135 2060);
DISPLAY 0.489362 (-6135 2060);
FORCEPROP 2 LASTPROP $XRERR UNIQUE?
J 0
(-6375 2060);
DISPLAY 0.638298 (-6375 2060);
PAINT MONO (-6375 2060);
DISPLAY INVISIBLE (-6375 2060);
WIRE 16 -1 (-6400 1100)(-5300 1100);
FORCEPROP 2 LAST SIG_NAME TP_M_K_CPU1_SA_TEST39K
J 0
(-6385 1110);
DISPLAY 0.489362 (-6385 1110);
FORCEPROP 2 LASTPROP $XRERR UNIQUE?
J 0
(-6640 1100);
DISPLAY 0.638298 (-6640 1100);
PAINT MONO (-6640 1100);
DISPLAY INVISIBLE (-6640 1100);
WIRE 16 -1 (-6400 2850)(-5300 2850);
FORCEPROP 2 LAST SIG_NAME M_K_CPU1_CLK_DN<0>
J 0
(-6400 2860);
DISPLAY 0.489362 (-6400 2860);
WIRE 16 -1 (-6400 2900)(-5300 2900);
FORCEPROP 2 LAST SIG_NAME M_K_CPU1_CLK_DP<0>
J 0
(-6400 2910);
DISPLAY 0.489362 (-6400 2910);
WIRE 16 -1 (-6400 2750)(-5300 2750);
FORCEPROP 2 LAST SIG_NAME M_K_CPU1_SA_CS_N<0>
J 0
(-6400 2760);
DISPLAY 0.489362 (-6400 2760);
WIRE 16 -1 (-6400 2700)(-5300 2700);
FORCEPROP 2 LAST SIG_NAME M_K_CPU1_SA_CS_N<1>
J 0
(-6400 2710);
DISPLAY 0.489362 (-6400 2710);
WIRE 16 -1 (-6400 2600)(-5300 2600);
FORCEPROP 2 LAST SIG_NAME M_K_CPU1_SA_RSP<0>
J 0
(-6400 2610);
DISPLAY 0.489362 (-6400 2610);
WIRE 16 -1 (-6400 2500)(-5300 2500);
FORCEPROP 2 LAST SIG_NAME M_K_CPU1_SA_PAR
J 0
(-6400 2510);
DISPLAY 0.489362 (-6400 2510);
WIRE 16 -1 (-6400 2400)(-5300 2400);
FORCEPROP 2 LAST SIG_NAME M_K_CPU1_SB_CS_N<0>
J 0
(-6400 2410);
DISPLAY 0.489362 (-6400 2410);
WIRE 16 -1 (-6400 2350)(-5300 2350);
FORCEPROP 2 LAST SIG_NAME M_K_CPU1_SB_CS_N<1>
J 0
(-6400 2360);
DISPLAY 0.489362 (-6400 2360);
WIRE 16 -1 (-6400 2250)(-5300 2250);
FORCEPROP 2 LAST SIG_NAME M_K_CPU1_SB_RSP<0>
J 0
(-6400 2260);
DISPLAY 0.489362 (-6400 2260);
WIRE 16 -1 (-6400 2150)(-5300 2150);
FORCEPROP 2 LAST SIG_NAME M_K_CPU1_SB_PAR
J 0
(-6400 2160);
DISPLAY 0.489362 (-6400 2160);
WIRE 16 -1 (-6400 1950)(-5300 1950);
FORCEPROP 2 LAST SIG_NAME M_K_CPU1_RESET_N
J 0
(-6400 1960);
DISPLAY 0.489362 (-6400 1960);
WIRE 16 -1 (-5800 3050)(-5300 3050);
WIRE 16 -1 (-5800 3750)(-5300 3750);
WIRE 16 -1 (-5800 3450)(-5300 3450);
WIRE 16 -1 (-5800 3100)(-5300 3100);
WIRE 16 -1 (-5800 3500)(-5300 3500);
WIRE 16 -1 (-5800 3150)(-5300 3150);
WIRE 16 -1 (-5800 3550)(-5300 3550);
WIRE 16 -1 (-5800 3200)(-5300 3200);
WIRE 16 -1 (-5800 3900)(-5300 3900);
WIRE 16 -1 (-5800 3600)(-5300 3600);
WIRE 16 -1 (-5800 3250)(-5300 3250);
WIRE 16 -1 (-5800 4000)(-5300 4000);
WIRE 16 -1 (-5800 3650)(-5300 3650);
WIRE 16 -1 (-5800 3300)(-5300 3300);
WIRE 16 -1 (-5800 3700)(-5300 3700);
WIRE 16 -1 (-5800 3350)(-5300 3350);
WIRE 16 -1 (-5600 3950)(-5300 3950);
WIRE 16 -1 (-5600 4050)(-5300 4050);
WIRE 16 -1 (-5800 4300)(-5300 4300);
WIRE 16 -1 (-5800 4400)(-5300 4400);
WIRE 16 -1 (-5800 4950)(-5300 4950);
WIRE 16 -1 (-5800 4500)(-5300 4500);
WIRE 16 -1 (-5800 5050)(-5300 5050);
WIRE 16 -1 (-5800 4600)(-5300 4600);
WIRE 16 -1 (-5800 4700)(-5300 4700);
WIRE 16 -1 (-5800 4800)(-5300 4800);
WIRE 16 -1 (-5800 4100)(-5300 4100);
WIRE 16 -1 (-5800 4200)(-5300 4200);
WIRE 16 -1 (-5600 4150)(-5300 4150);
WIRE 16 -1 (-5600 4250)(-5300 4250);
WIRE 16 -1 (-5600 4350)(-5300 4350);
WIRE 16 -1 (-5600 4450)(-5300 4450);
WIRE 16 -1 (-5600 4550)(-5300 4550);
WIRE 16 -1 (-5600 4750)(-5300 4750);
WIRE 16 -1 (-5600 4850)(-5300 4850);
WIRE 16 -1 (-5600 5000)(-5300 5000);
WIRE 16 -1 (-5600 5100)(-5300 5100);
WIRE 16 -1 (-5600 4650)(-5300 4650);
WIRE 16 -1 (-5800 5150)(-5300 5150);
WIRE 16 -1 (-5800 5250)(-5300 5250);
WIRE 16 -1 (-5800 5350)(-5300 5350);
WIRE 16 -1 (-5800 5450)(-5300 5450);
WIRE 16 -1 (-5800 5550)(-5300 5550);
WIRE 16 -1 (-5800 5650)(-5300 5650);
WIRE 16 -1 (-5800 5750)(-5300 5750);
WIRE 16 -1 (-5800 5850)(-5300 5850);
WIRE 16 -1 (-5600 5200)(-5300 5200);
WIRE 16 -1 (-5600 5300)(-5300 5300);
WIRE 16 -1 (-5600 5400)(-5300 5400);
WIRE 16 -1 (-5600 5500)(-5300 5500);
WIRE 16 -1 (-5600 5600)(-5300 5600);
WIRE 16 -1 (-5600 5700)(-5300 5700);
WIRE 16 -1 (-5600 5800)(-5300 5800);
WIRE 16 -1 (-5600 5900)(-5300 5900);
WIRE 16 -1 (-3700 1500)(-3275 1500);
WIRE 16 -1 (-3700 1550)(-3275 1550);
WIRE 16 -1 (-3700 1600)(-3275 1600);
WIRE 16 -1 (-3700 1650)(-3275 1650);
WIRE 16 -1 (-3700 1700)(-3275 1700);
WIRE 16 -1 (-3700 1750)(-3275 1750);
WIRE 16 -1 (-3700 1950)(-3275 1950);
WIRE 16 -1 (-3700 1800)(-3275 1800);
WIRE 16 -1 (-3700 2000)(-3275 2000);
WIRE 16 -1 (-3700 1850)(-3275 1850);
WIRE 16 -1 (-3700 2500)(-3275 2500);
WIRE 16 -1 (-3700 2550)(-3275 2550);
WIRE 16 -1 (-3700 2600)(-3275 2600);
WIRE 16 -1 (-3700 2650)(-3275 2650);
WIRE 16 -1 (-3700 2700)(-3275 2700);
WIRE 16 -1 (-3700 2750)(-3275 2750);
WIRE 16 -1 (-3700 2850)(-3275 2850);
WIRE 16 -1 (-3700 2900)(-3275 2900);
WIRE 16 -1 (-3700 2950)(-3275 2950);
WIRE 16 -1 (-3700 3000)(-3275 3000);
WIRE 16 -1 (-3700 2400)(-3275 2400);
WIRE 16 -1 (-3700 2050)(-3275 2050);
WIRE 16 -1 (-3700 2450)(-3275 2450);
WIRE 16 -1 (-3700 2100)(-3275 2100);
WIRE 16 -1 (-3700 2150)(-3275 2150);
WIRE 16 -1 (-3700 2200)(-3275 2200);
WIRE 16 -1 (-3700 2250)(-3275 2250);
WIRE 16 -1 (-3700 2300)(-3275 2300);
WIRE 16 -1 (-3700 3050)(-3275 3050);
WIRE 16 -1 (-3700 3600)(-3275 3600);
WIRE 16 -1 (-3700 3100)(-3275 3100);
WIRE 16 -1 (-3700 3650)(-3275 3650);
WIRE 16 -1 (-3700 3150)(-3275 3150);
WIRE 16 -1 (-3700 3750)(-3275 3750);
WIRE 16 -1 (-3700 3200)(-3275 3200);
WIRE 16 -1 (-3700 3800)(-3275 3800);
WIRE 16 -1 (-3700 3300)(-3275 3300);
WIRE 16 -1 (-3700 3850)(-3275 3850);
WIRE 16 -1 (-3700 3350)(-3275 3350);
WIRE 16 -1 (-3700 3900)(-3275 3900);
WIRE 16 -1 (-3700 3400)(-3275 3400);
WIRE 16 -1 (-3700 3950)(-3275 3950);
WIRE 16 -1 (-3700 3450)(-3275 3450);
WIRE 16 -1 (-3700 4000)(-3275 4000);
WIRE 16 -1 (-3700 3500)(-3275 3500);
WIRE 16 -1 (-3700 4050)(-3275 4050);
WIRE 16 -1 (-3700 3550)(-3275 3550);
WIRE 16 -1 (-3700 4850)(-3275 4850);
WIRE 16 -1 (-3700 4900)(-3275 4900);
WIRE 16 -1 (-3700 4300)(-3275 4300);
WIRE 16 -1 (-3700 4950)(-3275 4950);
WIRE 16 -1 (-3700 4350)(-3275 4350);
WIRE 16 -1 (-3700 5000)(-3275 5000);
WIRE 16 -1 (-3700 4400)(-3275 4400);
WIRE 16 -1 (-3700 5100)(-3275 5100);
WIRE 16 -1 (-3700 4450)(-3275 4450);
WIRE 16 -1 (-3700 4100)(-3275 4100);
WIRE 16 -1 (-3700 4500)(-3275 4500);
WIRE 16 -1 (-3700 4550)(-3275 4550);
WIRE 16 -1 (-3700 4650)(-3275 4650);
WIRE 16 -1 (-3700 4700)(-3275 4700);
WIRE 16 -1 (-3700 4750)(-3275 4750);
WIRE 16 -1 (-3700 4800)(-3275 4800);
WIRE 16 -1 (-3700 4200)(-3275 4200);
WIRE 16 -1 (-3700 4250)(-3275 4250);
WIRE 16 -1 (-3700 5400)(-3275 5400);
WIRE 16 -1 (-3700 5450)(-3275 5450);
WIRE 16 -1 (-3700 5550)(-3275 5550);
WIRE 16 -1 (-3700 5600)(-3275 5600);
WIRE 16 -1 (-3700 5650)(-3275 5650);
WIRE 16 -1 (-3700 5700)(-3275 5700);
WIRE 16 -1 (-3700 5750)(-3275 5750);
WIRE 16 -1 (-3700 5800)(-3275 5800);
WIRE 16 -1 (-3700 5850)(-3275 5850);
WIRE 16 -1 (-3700 5900)(-3275 5900);
WIRE 16 -1 (-3700 5150)(-3275 5150);
WIRE 16 -1 (-3700 5200)(-3275 5200);
WIRE 16 -1 (-3700 5250)(-3275 5250);
WIRE 16 -1 (-3700 5300)(-3275 5300);
WIRE 16 -1 (-3700 5350)(-3275 5350);
QUIT
